FILE_TYPE = MACRO_DRAWING;
SET COLOR_WIRE YELLOW;
SET COLOR_PROP MONO;
SET COLOR_DOT WHITE;
SET COLOR_ARC YELLOW;
SET COLOR_BODY GREEN;
SET COLOR_NOTE MONO;
SET PROP_DISPLAY VALUE;
SET PAGE_NUMBER P98;
FORCEADD PVDDQ_ABC..1
(-1800 4600);
FORCEPROP 3 LASTPIN (-1800 4550) SIG_NAME PVDDQ_ABC\g
J 0
(-1790 4560);
DISPLAY 0.659574 (-1790 4560);
PAINT MONO (-1790 4560);
DISPLAY INVISIBLE (-1790 4560);
FORCEPROP 1 LAST VOLTAGE 1.2V
J 0
(-1845 4557);
DISPLAY 0.340426 (-1845 4557);
PAINT SKYBLUE (-1845 4557);
DISPLAY INVISIBLE (-1845 4557);
FORCEPROP 2 LAST CDS_LIB mstr_symbols
J 0
(-1800 4600);
PAINT ORANGE (-1800 4600);
DISPLAY INVISIBLE (-1800 4600);
FORCEPROP 1 LAST BODY_TYPE PLUMBING
J 0
(-1845 4557);
DISPLAY 0.340426 (-1845 4557);
PAINT GREEN (-1845 4557);
DISPLAY INVISIBLE (-1845 4557);
FORCEPROP 1 LAST PATH I1
J 0
(-1750 4625);
DISPLAY 0.872340 (-1750 4625);
PAINT AQUA (-1750 4625);
DISPLAY INVISIBLE (-1750 4625);
FORCEPROP 1 LAST HDL_POWER PVDDQ_ABC
J 1
(-1800 4650);
DISPLAY 0.872340 (-1800 4650);
PAINT GREEN (-1800 4650);
DISPLAY INVISIBLE (-1800 4650);
FORCEADD PVDDQ_DEF..1
(-1800 2925);
FORCEPROP 3 LASTPIN (-1800 2875) SIG_NAME PVDDQ_DEF\g
J 0
(-1790 2885);
DISPLAY 0.659574 (-1790 2885);
PAINT MONO (-1790 2885);
DISPLAY INVISIBLE (-1790 2885);
FORCEPROP 1 LAST VOLTAGE 1.2V
J 0
(-1845 2882);
DISPLAY 0.340426 (-1845 2882);
PAINT SKYBLUE (-1845 2882);
DISPLAY INVISIBLE (-1845 2882);
FORCEPROP 2 LAST CDS_LIB mstr_symbols
J 0
(-1800 2925);
PAINT ORANGE (-1800 2925);
DISPLAY INVISIBLE (-1800 2925);
FORCEPROP 1 LAST BODY_TYPE PLUMBING
J 0
(-1845 2882);
DISPLAY 0.340426 (-1845 2882);
PAINT GREEN (-1845 2882);
DISPLAY INVISIBLE (-1845 2882);
FORCEPROP 1 LAST PATH I10
J 0
(-1750 2950);
DISPLAY 0.872340 (-1750 2950);
PAINT AQUA (-1750 2950);
DISPLAY INVISIBLE (-1750 2950);
FORCEPROP 1 LAST HDL_POWER PVDDQ_DEF
J 1
(-1800 2975);
DISPLAY 0.872340 (-1800 2975);
PAINT GREEN (-1800 2975);
DISPLAY INVISIBLE (-1800 2975);
FORCEADD OFFPAGE..2
(-1375 2350);
FORCEPROP 2 LAST $XR0 49 
J 0
(-1186 2350);
DISPLAY 0.638298 (-1186 2350);
PAINT MONO (-1186 2350);
FORCEPROP 2 LAST $XR1 50 
J 0
(-1096 2350);
DISPLAY 0.638298 (-1096 2350);
PAINT MONO (-1096 2350);
FORCEPROP 2 LAST CDS_LIB mstr_standard
J 0
(-1375 2350);
PAINT MONO (-1375 2350);
DISPLAY INVISIBLE (-1375 2350);
FORCEPROP 1 LAST OFFPAGE TRUE
J 0
(-1050 2225);
PAINT GREEN (-1050 2225);
DISPLAY INVISIBLE (-1050 2225);
FORCEPROP 1 LAST COMMENT_BODY TRUE
J 0
(-1420 2255);
DISPLAY 1.170213 (-1420 2255);
PAINT GREEN (-1420 2255);
DISPLAY INVISIBLE (-1420 2255);
FORCEPROP 2 LAST PATH I11
J 0
(-1075 2400);
DISPLAY 1.021277 (-1075 2400);
PAINT ORANGE (-1075 2400);
DISPLAY INVISIBLE (-1075 2400);
FORCEADD RES..2
R 2
(-1725 2025);
FORCEPROP 1 LAST LOCATION R6L16
J 2
(-1770 2150);
DISPLAY 0.617021 (-1770 2150);
PAINT AQUA (-1770 2150);
FORCEPROP 1 LAST PART_NUMBER G21796-026
J 2
(-1765 1900);
DISPLAY 0.617021 (-1765 1900);
PAINT BLUE (-1765 1900);
FORCEPROP 1 LAST VALUE 1.00K
J 2
(-1770 2100);
DISPLAY 0.617021 (-1770 2100);
PAINT SKYBLUE (-1770 2100);
FORCEPROP 1 LAST TOLERANCE 1%
J 2
(-1770 2050);
DISPLAY 0.617021 (-1770 2050);
PAINT SKYBLUE (-1770 2050);
FORCEPROP 1 LAST PACK_TYPE 0402
J 2
(-1765 1850);
DISPLAY 0.617021 (-1765 1850);
PAINT SKYBLUE (-1765 1850);
FORCEPROP 1 LAST MATERIAL CHIP
J 2
(-1765 1950);
DISPLAY 0.617021 (-1765 1950);
PAINT SKYBLUE (-1765 1950);
FORCEPROP 1 LAST WATTAGE 1/16W
J 2
(-1765 2000);
DISPLAY 0.617021 (-1765 2000);
PAINT SKYBLUE (-1765 2000);
FORCEPROP 1 LASTPIN (-1725 1925) $PN 2
J 2
(-1730 1935);
DISPLAY 0.617021 (-1730 1935);
PAINT ORANGE (-1730 1935);
FORCEPROP 1 LASTPIN (-1725 2125) $PN 1
J 2
(-1730 2087);
DISPLAY 0.617021 (-1730 2087);
PAINT ORANGE (-1730 2087);
FORCEPROP 2 LAST CDS_LIB mstr_discrete
J 0
(-1725 2025);
PAINT ORANGE (-1725 2025);
DISPLAY INVISIBLE (-1725 2025);
FORCEPROP 2 LAST BOM_COST PROC_SOCKET
J 2
(-1725 2025);
PAINT MONO (-1725 2025);
DISPLAY INVISIBLE (-1725 2025);
FORCEPROP 2 LAST SEC_TYPE 0402
J 0
(-1775 2250);
DISPLAY 1.021277 (-1775 2250);
PAINT ORANGE (-1775 2250);
DISPLAY INVISIBLE (-1775 2250);
FORCEPROP 2 LAST SEC 1
J 0
(-1775 2250);
DISPLAY 0.680851 (-1775 2250);
PAINT MONO (-1775 2250);
DISPLAY INVISIBLE (-1775 2250);
FORCEPROP 2 LAST CDS_LOCATION R6L16
J 2
(-1770 2150);
DISPLAY 0.617021 (-1770 2150);
PAINT AQUA (-1770 2150);
DISPLAY INVISIBLE (-1770 2150);
FORCEPROP 1 LAST PATH I12
J 2
(-1775 2200);
DISPLAY 0.978723 (-1775 2200);
PAINT WHITE (-1775 2200);
DISPLAY INVISIBLE (-1775 2200);
FORCEPROP 2 LAST ROOM PROC
J 2
(-1775 2200);
PAINT PEACH (-1775 2200);
DISPLAY INVISIBLE (-1775 2200);
FORCEADD GND..1
(-2025 1700);
FORCEPROP 3 LASTPIN (-2025 1750) SIG_NAME GND\g
J 0
(-2015 1760);
DISPLAY 0.659574 (-2015 1760);
PAINT MONO (-2015 1760);
DISPLAY INVISIBLE (-2015 1760);
FORCEPROP 1 LAST VOLTAGE 0
J 0
(-2025 1700);
PAINT SKYBLUE (-2025 1700);
DISPLAY INVISIBLE (-2025 1700);
FORCEPROP 2 LAST CDS_LIB mstr_symbols
J 0
(-2025 1700);
PAINT MONO (-2025 1700);
DISPLAY INVISIBLE (-2025 1700);
FORCEPROP 1 LAST SIZE 1B
J 0
(-1950 1650);
DISPLAY 1.170213 (-1950 1650);
PAINT GREEN (-1950 1650);
DISPLAY INVISIBLE (-1950 1650);
FORCEPROP 1 LAST BODY_TYPE PLUMBING
J 0
(-2070 1657);
DISPLAY 0.340426 (-2070 1657);
PAINT GREEN (-2070 1657);
DISPLAY INVISIBLE (-2070 1657);
FORCEPROP 1 LAST PATH I13
J 0
(-1950 1700);
DISPLAY 0.872340 (-1950 1700);
PAINT AQUA (-1950 1700);
DISPLAY INVISIBLE (-1950 1700);
FORCEPROP 1 LAST HDL_POWER GND
J 0
(-2025 1850);
DISPLAY 1.170213 (-2025 1850);
PAINT GREEN (-2025 1850);
DISPLAY INVISIBLE (-2025 1850);
FORCEADD RES..1
(-2025 2350);
FORCEPROP 1 LAST LOCATION R6M2
J 0
(-2050 2425);
DISPLAY 0.617021 (-2050 2425);
PAINT AQUA (-2050 2425);
FORCEPROP 1 LAST PART_NUMBER G21796-274
J 0
(-2150 2200);
DISPLAY 0.617021 (-2150 2200);
PAINT BLUE (-2150 2200);
FORCEPROP 1 LAST VALUE 2
J 2
(-2100 2300);
DISPLAY 0.617021 (-2100 2300);
PAINT SKYBLUE (-2100 2300);
FORCEPROP 1 LAST TOLERANCE 1.0%
J 0
(-1925 2250);
DISPLAY 0.617021 (-1925 2250);
PAINT SKYBLUE (-1925 2250);
FORCEPROP 1 LAST PACK_TYPE 0402
J 0
(-2150 2250);
DISPLAY 0.617021 (-2150 2250);
PAINT SKYBLUE (-2150 2250);
FORCEPROP 1 LAST MATERIAL CHIP
J 0
(-1800 2300);
DISPLAY 0.617021 (-1800 2300);
PAINT SKYBLUE (-1800 2300);
FORCEPROP 1 LAST WATTAGE 1/16W
J 2
(-1850 2300);
DISPLAY 0.617021 (-1850 2300);
PAINT SKYBLUE (-1850 2300);
FORCEPROP 1 LASTPIN (-1925 2350) $PN 2
J 0
(-1963 2362);
DISPLAY 0.617021 (-1963 2362);
PAINT MONO (-1963 2362);
FORCEPROP 1 LASTPIN (-2125 2350) $PN 1
J 0
(-2113 2362);
DISPLAY 0.617021 (-2113 2362);
PAINT MONO (-2113 2362);
FORCEPROP 2 LAST CDS_LIB mstr_discrete
J 0
(-2025 2350);
PAINT ORANGE (-2025 2350);
DISPLAY INVISIBLE (-2025 2350);
FORCEPROP 2 LAST BOM_COST PROC_SOCKET
J 0
(-2025 2350);
PAINT MONO (-2025 2350);
DISPLAY INVISIBLE (-2025 2350);
FORCEPROP 2 LAST SEC_TYPE 0402
J 0
(-2075 2550);
PAINT MONO (-2075 2550);
DISPLAY INVISIBLE (-2075 2550);
FORCEPROP 2 LAST SEC 1
J 0
(-2075 2550);
DISPLAY 0.936170 (-2075 2550);
PAINT MONO (-2075 2550);
DISPLAY INVISIBLE (-2075 2550);
FORCEPROP 2 LAST CDS_LOCATION R6M2
J 0
(-2050 2425);
DISPLAY 0.617021 (-2050 2425);
PAINT AQUA (-2050 2425);
DISPLAY INVISIBLE (-2050 2425);
FORCEPROP 1 LAST PATH I14
J 0
(-2075 2500);
DISPLAY 0.978723 (-2075 2500);
PAINT WHITE (-2075 2500);
DISPLAY INVISIBLE (-2075 2500);
FORCEPROP 0 LAST ROOM PROC
J 0
(-2100 2275);
DISPLAY 0.617021 (-2100 2275);
PAINT ORANGE (-2100 2275);
DISPLAY INVISIBLE (-2100 2275);
FORCEADD OFFPAGE..1
(-2750 2350);
FORCEPROP 2 LAST $XR0 21 
J 0
(-2971 2350);
DISPLAY 0.638298 (-2971 2350);
PAINT MONO (-2971 2350);
FORCEPROP 2 LAST CDS_LIB mstr_standard
J 0
(-2750 2350);
PAINT MONO (-2750 2350);
DISPLAY INVISIBLE (-2750 2350);
FORCEPROP 1 LAST OFFPAGE TRUE
J 0
(-2425 2225);
PAINT GREEN (-2425 2225);
DISPLAY INVISIBLE (-2425 2225);
FORCEPROP 1 LAST COMMENT_BODY TRUE
J 0
(-2625 2250);
DISPLAY 1.170213 (-2625 2250);
PAINT GREEN (-2625 2250);
DISPLAY INVISIBLE (-2625 2250);
FORCEPROP 2 LAST PATH I16
J 0
(-3000 2400);
DISPLAY 1.021277 (-3000 2400);
PAINT ORANGE (-3000 2400);
DISPLAY INVISIBLE (-3000 2400);
FORCEADD OFFPAGE..2
(-1375 4025);
FORCEPROP 2 LAST $XR0 43 
J 0
(-1186 4025);
DISPLAY 0.638298 (-1186 4025);
PAINT MONO (-1186 4025);
FORCEPROP 2 LAST $XR1 44 
J 0
(-1096 4025);
DISPLAY 0.638298 (-1096 4025);
PAINT MONO (-1096 4025);
FORCEPROP 2 LAST CDS_LIB mstr_standard
J 0
(-1375 4025);
PAINT MONO (-1375 4025);
DISPLAY INVISIBLE (-1375 4025);
FORCEPROP 1 LAST OFFPAGE TRUE
J 0
(-1050 3900);
PAINT GREEN (-1050 3900);
DISPLAY INVISIBLE (-1050 3900);
FORCEPROP 1 LAST COMMENT_BODY TRUE
J 0
(-1420 3930);
DISPLAY 1.170213 (-1420 3930);
PAINT GREEN (-1420 3930);
DISPLAY INVISIBLE (-1420 3930);
FORCEPROP 2 LAST PATH I3
J 0
(-1075 4075);
DISPLAY 1.021277 (-1075 4075);
PAINT ORANGE (-1075 4075);
DISPLAY INVISIBLE (-1075 4075);
FORCEADD CAP_A..1
(-2250 2050);
FORCEPROP 1 LAST LOCATION C6M2
J 0
(-2200 2150);
DISPLAY 0.617021 (-2200 2150);
PAINT AQUA (-2200 2150);
FORCEPROP 1 LAST PART_NUMBER A36096-045
J 0
(-2200 1900);
DISPLAY 0.617021 (-2200 1900);
PAINT BLUE (-2200 1900);
FORCEPROP 1 LAST VALUE 0.01UF
J 0
(-2200 2100);
DISPLAY 0.617021 (-2200 2100);
PAINT SKYBLUE (-2200 2100);
FORCEPROP 1 LAST TOLERANCE 10%
J 0
(-2200 2000);
DISPLAY 0.617021 (-2200 2000);
PAINT SKYBLUE (-2200 2000);
FORCEPROP 1 LAST PACK_TYPE 0402V
J 0
(-2200 1850);
DISPLAY 0.617021 (-2200 1850);
PAINT SKYBLUE (-2200 1850);
FORCEPROP 1 LAST VOLTAGE 25V
J 0
(-2200 2050);
DISPLAY 0.617021 (-2200 2050);
PAINT SKYBLUE (-2200 2050);
FORCEPROP 1 LAST MATERIAL X7R
J 0
(-2200 1950);
DISPLAY 0.617021 (-2200 1950);
PAINT SKYBLUE (-2200 1950);
FORCEPROP 1 LASTPIN (-2250 2150) $PN 1
J 0
(-2240 2130);
DISPLAY 0.617021 (-2240 2130);
PAINT ORANGE (-2240 2130);
FORCEPROP 1 LASTPIN (-2250 1950) $PN 2
J 0
(-2240 1930);
DISPLAY 0.617021 (-2240 1930);
PAINT ORANGE (-2240 1930);
FORCEPROP 2 LAST CDS_LOCATION C6M2
J 0
(-2200 2150);
DISPLAY 0.617021 (-2200 2150);
PAINT AQUA (-2200 2150);
DISPLAY INVISIBLE (-2200 2150);
FORCEPROP 2 LAST BOM_COST SM_CONTROLLER
J 0
(-2250 2050);
PAINT MONO (-2250 2050);
DISPLAY INVISIBLE (-2250 2050);
FORCEPROP 2 LAST CDS_LIB dev_discrete
J 0
(-2250 2050);
PAINT ORANGE (-2250 2050);
DISPLAY INVISIBLE (-2250 2050);
FORCEPROP 2 LAST CDS_SEC 1
J 0
(-2200 2200);
PAINT ORANGE (-2200 2200);
DISPLAY INVISIBLE (-2200 2200);
FORCEPROP 2 LAST SEC_TYPE 0402V
J 0
(-2200 2250);
DISPLAY 1.021277 (-2200 2250);
PAINT ORANGE (-2200 2250);
DISPLAY INVISIBLE (-2200 2250);
FORCEPROP 2 LAST SEC 1
J 0
(-2200 2250);
DISPLAY 0.680851 (-2200 2250);
PAINT MONO (-2200 2250);
DISPLAY INVISIBLE (-2200 2250);
FORCEPROP 1 LAST PATH I33
J 0
(-2200 2200);
DISPLAY 0.978723 (-2200 2200);
PAINT WHITE (-2200 2200);
DISPLAY INVISIBLE (-2200 2200);
FORCEPROP 0 LAST ROOM MEM
J 0
(-2200 1800);
DISPLAY 0.978723 (-2200 1800);
PAINT ORANGE (-2200 1800);
DISPLAY INVISIBLE (-2200 1800);
FORCEADD RES..2
R 2
(-1800 4350);
FORCEPROP 1 LAST LOCATION R4F4
J 2
(-1845 4475);
DISPLAY 0.617021 (-1845 4475);
PAINT AQUA (-1845 4475);
FORCEPROP 1 LAST PART_NUMBER G21796-026
J 2
(-1840 4225);
DISPLAY 0.617021 (-1840 4225);
PAINT BLUE (-1840 4225);
FORCEPROP 1 LAST VALUE 1.00K
J 2
(-1845 4425);
DISPLAY 0.617021 (-1845 4425);
PAINT SKYBLUE (-1845 4425);
FORCEPROP 1 LAST TOLERANCE 1%
J 2
(-1845 4375);
DISPLAY 0.617021 (-1845 4375);
PAINT SKYBLUE (-1845 4375);
FORCEPROP 1 LAST PACK_TYPE 0402
J 2
(-1840 4175);
DISPLAY 0.617021 (-1840 4175);
PAINT SKYBLUE (-1840 4175);
FORCEPROP 1 LAST MATERIAL CHIP
J 2
(-1840 4275);
DISPLAY 0.617021 (-1840 4275);
PAINT SKYBLUE (-1840 4275);
FORCEPROP 1 LAST WATTAGE 1/16W
J 2
(-1840 4325);
DISPLAY 0.617021 (-1840 4325);
PAINT SKYBLUE (-1840 4325);
FORCEPROP 1 LASTPIN (-1800 4250) $PN 2
J 2
(-1805 4260);
DISPLAY 0.617021 (-1805 4260);
PAINT ORANGE (-1805 4260);
FORCEPROP 1 LASTPIN (-1800 4450) $PN 1
J 2
(-1805 4412);
DISPLAY 0.617021 (-1805 4412);
PAINT ORANGE (-1805 4412);
FORCEPROP 2 LAST SEC_TYPE 0402
J 0
(-1850 4575);
DISPLAY 1.021277 (-1850 4575);
PAINT ORANGE (-1850 4575);
DISPLAY INVISIBLE (-1850 4575);
FORCEPROP 2 LAST CDS_LIB mstr_discrete
J 0
(-1800 4350);
PAINT ORANGE (-1800 4350);
DISPLAY INVISIBLE (-1800 4350);
FORCEPROP 2 LAST BOM_COST SM_CONTROLLER
J 2
(-1800 4350);
PAINT MONO (-1800 4350);
DISPLAY INVISIBLE (-1800 4350);
FORCEPROP 2 LAST SEC 1
J 0
(-1850 4575);
DISPLAY 0.680851 (-1850 4575);
PAINT MONO (-1850 4575);
DISPLAY INVISIBLE (-1850 4575);
FORCEPROP 2 LAST CDS_LOCATION R4F4
J 2
(-1845 4475);
DISPLAY 0.617021 (-1845 4475);
PAINT AQUA (-1845 4475);
DISPLAY INVISIBLE (-1845 4475);
FORCEPROP 1 LAST PATH I36
J 2
(-1850 4525);
DISPLAY 0.978723 (-1850 4525);
PAINT WHITE (-1850 4525);
DISPLAY INVISIBLE (-1850 4525);
FORCEPROP 2 LAST ROOM MEM
J 2
(-1850 4525);
PAINT PEACH (-1850 4525);
DISPLAY INVISIBLE (-1850 4525);
FORCEADD PVDDQ_ABC..1
(250 4600);
FORCEPROP 3 LASTPIN (250 4550) SIG_NAME PVDDQ_ABC\g
J 0
(260 4560);
DISPLAY 0.659574 (260 4560);
PAINT MONO (260 4560);
DISPLAY INVISIBLE (260 4560);
FORCEPROP 1 LAST VOLTAGE 1.2V
J 0
(205 4557);
DISPLAY 0.340426 (205 4557);
PAINT SKYBLUE (205 4557);
DISPLAY INVISIBLE (205 4557);
FORCEPROP 2 LAST CDS_LIB mstr_symbols
J 0
(250 4600);
PAINT ORANGE (250 4600);
DISPLAY INVISIBLE (250 4600);
FORCEPROP 1 LAST BODY_TYPE PLUMBING
J 0
(205 4557);
DISPLAY 0.340426 (205 4557);
PAINT GREEN (205 4557);
DISPLAY INVISIBLE (205 4557);
FORCEPROP 1 LAST PATH I37
J 0
(300 4625);
DISPLAY 0.872340 (300 4625);
PAINT AQUA (300 4625);
DISPLAY INVISIBLE (300 4625);
FORCEPROP 1 LAST HDL_POWER PVDDQ_ABC
J 1
(250 4650);
DISPLAY 0.872340 (250 4650);
PAINT GREEN (250 4650);
DISPLAY INVISIBLE (250 4650);
FORCEADD RES..2
R 2
(250 4350);
FORCEPROP 1 LAST LOCATION R4G2
J 2
(205 4475);
DISPLAY 0.617021 (205 4475);
PAINT AQUA (205 4475);
FORCEPROP 1 LAST PART_NUMBER G21796-026
J 2
(210 4225);
DISPLAY 0.617021 (210 4225);
PAINT BLUE (210 4225);
FORCEPROP 1 LAST VALUE 1.00K
J 2
(205 4425);
DISPLAY 0.617021 (205 4425);
PAINT SKYBLUE (205 4425);
FORCEPROP 1 LAST TOLERANCE 1%
J 2
(205 4375);
DISPLAY 0.617021 (205 4375);
PAINT SKYBLUE (205 4375);
FORCEPROP 1 LAST PACK_TYPE 0402
J 2
(210 4175);
DISPLAY 0.617021 (210 4175);
PAINT SKYBLUE (210 4175);
FORCEPROP 1 LAST MATERIAL CHIP
J 2
(210 4275);
DISPLAY 0.617021 (210 4275);
PAINT SKYBLUE (210 4275);
FORCEPROP 1 LAST WATTAGE 1/16W
J 2
(210 4325);
DISPLAY 0.617021 (210 4325);
PAINT SKYBLUE (210 4325);
FORCEPROP 1 LASTPIN (250 4250) $PN 2
J 2
(245 4260);
DISPLAY 0.617021 (245 4260);
PAINT ORANGE (245 4260);
FORCEPROP 1 LASTPIN (250 4450) $PN 1
J 2
(245 4412);
DISPLAY 0.617021 (245 4412);
PAINT ORANGE (245 4412);
FORCEPROP 2 LAST BOM_COST SM_CONTROLLER
J 2
(250 4350);
PAINT MONO (250 4350);
DISPLAY INVISIBLE (250 4350);
FORCEPROP 2 LAST CDS_LIB mstr_discrete
J 0
(250 4350);
PAINT ORANGE (250 4350);
DISPLAY INVISIBLE (250 4350);
FORCEPROP 2 LAST SEC_TYPE 0402
J 0
(200 4575);
DISPLAY 1.021277 (200 4575);
PAINT ORANGE (200 4575);
DISPLAY INVISIBLE (200 4575);
FORCEPROP 2 LAST SEC 1
J 0
(200 4575);
DISPLAY 0.680851 (200 4575);
PAINT MONO (200 4575);
DISPLAY INVISIBLE (200 4575);
FORCEPROP 2 LAST CDS_LOCATION R4G2
J 2
(205 4475);
DISPLAY 0.617021 (205 4475);
PAINT AQUA (205 4475);
DISPLAY INVISIBLE (205 4475);
FORCEPROP 1 LAST PATH I38
J 2
(200 4525);
DISPLAY 0.978723 (200 4525);
PAINT WHITE (200 4525);
DISPLAY INVISIBLE (200 4525);
FORCEPROP 2 LAST ROOM MEM
J 2
(200 4525);
PAINT PEACH (200 4525);
DISPLAY INVISIBLE (200 4525);
FORCEADD OFFPAGE..2
(675 4025);
FORCEPROP 2 LAST $XR0 45 
J 0
(864 4025);
DISPLAY 0.638298 (864 4025);
PAINT MONO (864 4025);
FORCEPROP 2 LAST $XR1 46 
J 0
(954 4025);
DISPLAY 0.638298 (954 4025);
PAINT MONO (954 4025);
FORCEPROP 2 LAST CDS_LIB mstr_standard
J 0
(675 4025);
PAINT MONO (675 4025);
DISPLAY INVISIBLE (675 4025);
FORCEPROP 1 LAST OFFPAGE TRUE
J 0
(1000 3900);
PAINT GREEN (1000 3900);
DISPLAY INVISIBLE (1000 3900);
FORCEPROP 1 LAST COMMENT_BODY TRUE
J 0
(630 3930);
DISPLAY 1.170213 (630 3930);
PAINT GREEN (630 3930);
DISPLAY INVISIBLE (630 3930);
FORCEPROP 2 LAST PATH I39
J 0
(850 4100);
DISPLAY 1.021277 (850 4100);
PAINT ORANGE (850 4100);
DISPLAY INVISIBLE (850 4100);
FORCEADD RES..2
R 2
(-1725 3700);
FORCEPROP 1 LAST LOCATION R4F5
J 2
(-1770 3825);
DISPLAY 0.617021 (-1770 3825);
PAINT AQUA (-1770 3825);
FORCEPROP 1 LAST PART_NUMBER G21796-026
J 2
(-1765 3575);
DISPLAY 0.617021 (-1765 3575);
PAINT BLUE (-1765 3575);
FORCEPROP 1 LAST VALUE 1.00K
J 2
(-1770 3775);
DISPLAY 0.617021 (-1770 3775);
PAINT SKYBLUE (-1770 3775);
FORCEPROP 1 LAST TOLERANCE 1%
J 2
(-1770 3725);
DISPLAY 0.617021 (-1770 3725);
PAINT SKYBLUE (-1770 3725);
FORCEPROP 1 LAST PACK_TYPE 0402
J 2
(-1765 3525);
DISPLAY 0.617021 (-1765 3525);
PAINT SKYBLUE (-1765 3525);
FORCEPROP 1 LAST MATERIAL CHIP
J 2
(-1765 3625);
DISPLAY 0.617021 (-1765 3625);
PAINT SKYBLUE (-1765 3625);
FORCEPROP 1 LAST WATTAGE 1/16W
J 2
(-1765 3675);
DISPLAY 0.617021 (-1765 3675);
PAINT SKYBLUE (-1765 3675);
FORCEPROP 1 LASTPIN (-1725 3600) $PN 2
J 2
(-1730 3610);
DISPLAY 0.617021 (-1730 3610);
PAINT ORANGE (-1730 3610);
FORCEPROP 1 LASTPIN (-1725 3800) $PN 1
J 2
(-1730 3762);
DISPLAY 0.617021 (-1730 3762);
PAINT ORANGE (-1730 3762);
FORCEPROP 2 LAST SEC_TYPE 0402
J 0
(-1775 3925);
DISPLAY 1.021277 (-1775 3925);
PAINT ORANGE (-1775 3925);
DISPLAY INVISIBLE (-1775 3925);
FORCEPROP 2 LAST BOM_COST PROC_SOCKET
J 2
(-1725 3700);
PAINT MONO (-1725 3700);
DISPLAY INVISIBLE (-1725 3700);
FORCEPROP 2 LAST CDS_LIB mstr_discrete
J 0
(-1725 3700);
PAINT ORANGE (-1725 3700);
DISPLAY INVISIBLE (-1725 3700);
FORCEPROP 2 LAST SEC 1
J 0
(-1775 3925);
DISPLAY 0.680851 (-1775 3925);
PAINT MONO (-1775 3925);
DISPLAY INVISIBLE (-1775 3925);
FORCEPROP 2 LAST CDS_LOCATION R4F5
J 2
(-1770 3825);
DISPLAY 0.617021 (-1770 3825);
PAINT AQUA (-1770 3825);
DISPLAY INVISIBLE (-1770 3825);
FORCEPROP 1 LAST PATH I4
J 2
(-1775 3875);
DISPLAY 0.978723 (-1775 3875);
PAINT WHITE (-1775 3875);
DISPLAY INVISIBLE (-1775 3875);
FORCEPROP 2 LAST ROOM PROC
J 2
(-1775 3875);
PAINT PEACH (-1775 3875);
DISPLAY INVISIBLE (-1775 3875);
FORCEADD RES..2
R 2
(325 3700);
FORCEPROP 1 LAST LOCATION R4G3
J 2
(280 3825);
DISPLAY 0.617021 (280 3825);
PAINT AQUA (280 3825);
FORCEPROP 1 LAST PART_NUMBER G21796-026
J 2
(285 3575);
DISPLAY 0.617021 (285 3575);
PAINT BLUE (285 3575);
FORCEPROP 1 LAST VALUE 1.00K
J 2
(280 3775);
DISPLAY 0.617021 (280 3775);
PAINT SKYBLUE (280 3775);
FORCEPROP 1 LAST TOLERANCE 1%
J 2
(280 3725);
DISPLAY 0.617021 (280 3725);
PAINT SKYBLUE (280 3725);
FORCEPROP 1 LAST PACK_TYPE 0402
J 2
(285 3525);
DISPLAY 0.617021 (285 3525);
PAINT SKYBLUE (285 3525);
FORCEPROP 1 LAST MATERIAL CHIP
J 2
(285 3625);
DISPLAY 0.617021 (285 3625);
PAINT SKYBLUE (285 3625);
FORCEPROP 1 LAST WATTAGE 1/16W
J 2
(285 3675);
DISPLAY 0.617021 (285 3675);
PAINT SKYBLUE (285 3675);
FORCEPROP 1 LASTPIN (325 3600) $PN 2
J 2
(320 3610);
DISPLAY 0.617021 (320 3610);
PAINT ORANGE (320 3610);
FORCEPROP 1 LASTPIN (325 3800) $PN 1
J 2
(320 3762);
DISPLAY 0.617021 (320 3762);
PAINT ORANGE (320 3762);
FORCEPROP 2 LAST CDS_LIB mstr_discrete
J 0
(325 3700);
PAINT ORANGE (325 3700);
DISPLAY INVISIBLE (325 3700);
FORCEPROP 2 LAST BOM_COST PROC_SOCKET
J 2
(325 3700);
PAINT MONO (325 3700);
DISPLAY INVISIBLE (325 3700);
FORCEPROP 2 LAST SEC_TYPE 0402
J 0
(275 3925);
DISPLAY 1.021277 (275 3925);
PAINT ORANGE (275 3925);
DISPLAY INVISIBLE (275 3925);
FORCEPROP 2 LAST SEC 1
J 0
(275 3925);
DISPLAY 0.680851 (275 3925);
PAINT MONO (275 3925);
DISPLAY INVISIBLE (275 3925);
FORCEPROP 2 LAST CDS_LOCATION R4G3
J 2
(280 3825);
DISPLAY 0.617021 (280 3825);
PAINT AQUA (280 3825);
DISPLAY INVISIBLE (280 3825);
FORCEPROP 1 LAST PATH I40
J 2
(275 3875);
DISPLAY 0.978723 (275 3875);
PAINT WHITE (275 3875);
DISPLAY INVISIBLE (275 3875);
FORCEPROP 2 LAST ROOM PROC
J 2
(275 3875);
PAINT PEACH (275 3875);
DISPLAY INVISIBLE (275 3875);
FORCEADD GND..1
(25 3375);
FORCEPROP 3 LASTPIN (25 3425) SIG_NAME GND\g
J 0
(35 3435);
DISPLAY 0.659574 (35 3435);
PAINT MONO (35 3435);
DISPLAY INVISIBLE (35 3435);
FORCEPROP 1 LAST VOLTAGE 0
J 0
(25 3375);
PAINT SKYBLUE (25 3375);
DISPLAY INVISIBLE (25 3375);
FORCEPROP 1 LAST SIZE 1B
J 0
(100 3325);
DISPLAY 1.170213 (100 3325);
PAINT GREEN (100 3325);
DISPLAY INVISIBLE (100 3325);
FORCEPROP 2 LAST CDS_LIB mstr_symbols
J 0
(25 3375);
PAINT MONO (25 3375);
DISPLAY INVISIBLE (25 3375);
FORCEPROP 1 LAST BODY_TYPE PLUMBING
J 0
(-20 3332);
DISPLAY 0.340426 (-20 3332);
PAINT GREEN (-20 3332);
DISPLAY INVISIBLE (-20 3332);
FORCEPROP 1 LAST PATH I41
J 0
(100 3375);
DISPLAY 0.872340 (100 3375);
PAINT AQUA (100 3375);
DISPLAY INVISIBLE (100 3375);
FORCEPROP 1 LAST HDL_POWER GND
J 0
(25 3525);
DISPLAY 1.170213 (25 3525);
PAINT GREEN (25 3525);
DISPLAY INVISIBLE (25 3525);
FORCEADD RES..1
(25 4025);
FORCEPROP 1 LAST LOCATION R4G1
J 0
(0 4100);
DISPLAY 0.617021 (0 4100);
PAINT AQUA (0 4100);
FORCEPROP 1 LAST PART_NUMBER G21796-274
J 0
(-100 3875);
DISPLAY 0.617021 (-100 3875);
PAINT BLUE (-100 3875);
FORCEPROP 1 LAST VALUE 2
J 2
(-50 3975);
DISPLAY 0.617021 (-50 3975);
PAINT SKYBLUE (-50 3975);
FORCEPROP 1 LAST TOLERANCE 1.0%
J 0
(125 3925);
DISPLAY 0.617021 (125 3925);
PAINT SKYBLUE (125 3925);
FORCEPROP 1 LAST PACK_TYPE 0402
J 0
(-100 3925);
DISPLAY 0.617021 (-100 3925);
PAINT SKYBLUE (-100 3925);
FORCEPROP 1 LAST MATERIAL CHIP
J 0
(250 3975);
DISPLAY 0.617021 (250 3975);
PAINT SKYBLUE (250 3975);
FORCEPROP 1 LAST WATTAGE 1/16W
J 2
(200 3975);
DISPLAY 0.617021 (200 3975);
PAINT SKYBLUE (200 3975);
FORCEPROP 1 LASTPIN (125 4025) $PN 2
J 0
(87 4037);
DISPLAY 0.617021 (87 4037);
PAINT MONO (87 4037);
FORCEPROP 1 LASTPIN (-75 4025) $PN 1
J 0
(-63 4037);
DISPLAY 0.617021 (-63 4037);
PAINT MONO (-63 4037);
FORCEPROP 2 LAST CDS_LIB mstr_discrete
J 0
(25 4025);
PAINT ORANGE (25 4025);
DISPLAY INVISIBLE (25 4025);
FORCEPROP 2 LAST BOM_COST PROC_SOCKET
J 0
(25 4025);
PAINT MONO (25 4025);
DISPLAY INVISIBLE (25 4025);
FORCEPROP 2 LAST SEC_TYPE 0402
J 0
(-25 4225);
PAINT MONO (-25 4225);
DISPLAY INVISIBLE (-25 4225);
FORCEPROP 2 LAST SEC 1
J 0
(-25 4225);
DISPLAY 0.936170 (-25 4225);
PAINT MONO (-25 4225);
DISPLAY INVISIBLE (-25 4225);
FORCEPROP 2 LAST CDS_LOCATION R4G1
J 0
(0 4100);
DISPLAY 0.617021 (0 4100);
PAINT AQUA (0 4100);
DISPLAY INVISIBLE (0 4100);
FORCEPROP 1 LAST PATH I42
J 0
(-25 4175);
DISPLAY 0.978723 (-25 4175);
PAINT WHITE (-25 4175);
DISPLAY INVISIBLE (-25 4175);
FORCEPROP 0 LAST ROOM PROC
J 0
(-50 3950);
DISPLAY 0.617021 (-50 3950);
PAINT ORANGE (-50 3950);
DISPLAY INVISIBLE (-50 3950);
FORCEADD CAP_A..1
(-200 3725);
FORCEPROP 1 LAST LOCATION C4G1
J 0
(-150 3825);
DISPLAY 0.617021 (-150 3825);
PAINT AQUA (-150 3825);
FORCEPROP 1 LAST PART_NUMBER A36096-045
J 0
(-150 3575);
DISPLAY 0.617021 (-150 3575);
PAINT BLUE (-150 3575);
FORCEPROP 1 LAST VALUE 0.01UF
J 0
(-150 3775);
DISPLAY 0.617021 (-150 3775);
PAINT SKYBLUE (-150 3775);
FORCEPROP 1 LAST TOLERANCE 10%
J 0
(-150 3675);
DISPLAY 0.617021 (-150 3675);
PAINT SKYBLUE (-150 3675);
FORCEPROP 1 LAST PACK_TYPE 0402V
J 0
(-150 3525);
DISPLAY 0.617021 (-150 3525);
PAINT SKYBLUE (-150 3525);
FORCEPROP 1 LAST VOLTAGE 25V
J 0
(-150 3725);
DISPLAY 0.617021 (-150 3725);
PAINT SKYBLUE (-150 3725);
FORCEPROP 1 LAST MATERIAL X7R
J 0
(-150 3625);
DISPLAY 0.617021 (-150 3625);
PAINT SKYBLUE (-150 3625);
FORCEPROP 1 LASTPIN (-200 3825) $PN 1
J 0
(-190 3805);
DISPLAY 0.617021 (-190 3805);
PAINT ORANGE (-190 3805);
FORCEPROP 1 LASTPIN (-200 3625) $PN 2
J 0
(-190 3605);
DISPLAY 0.617021 (-190 3605);
PAINT ORANGE (-190 3605);
FORCEPROP 2 LAST CDS_LOCATION C4G1
J 0
(-150 3825);
DISPLAY 0.617021 (-150 3825);
PAINT AQUA (-150 3825);
DISPLAY INVISIBLE (-150 3825);
FORCEPROP 2 LAST BOM_COST SM_CONTROLLER
J 0
(-200 3725);
PAINT MONO (-200 3725);
DISPLAY INVISIBLE (-200 3725);
FORCEPROP 2 LAST CDS_LIB dev_discrete
J 0
(-200 3725);
PAINT ORANGE (-200 3725);
DISPLAY INVISIBLE (-200 3725);
FORCEPROP 2 LAST CDS_SEC 1
J 0
(-150 3875);
PAINT ORANGE (-150 3875);
DISPLAY INVISIBLE (-150 3875);
FORCEPROP 2 LAST SEC_TYPE 0402V
J 0
(-150 3925);
DISPLAY 1.021277 (-150 3925);
PAINT ORANGE (-150 3925);
DISPLAY INVISIBLE (-150 3925);
FORCEPROP 2 LAST SEC 1
J 0
(-150 3925);
DISPLAY 0.680851 (-150 3925);
PAINT MONO (-150 3925);
DISPLAY INVISIBLE (-150 3925);
FORCEPROP 1 LAST PATH I43
J 0
(-150 3875);
DISPLAY 0.978723 (-150 3875);
PAINT WHITE (-150 3875);
DISPLAY INVISIBLE (-150 3875);
FORCEPROP 0 LAST ROOM MEM
J 0
(-150 3475);
DISPLAY 0.978723 (-150 3475);
PAINT ORANGE (-150 3475);
DISPLAY INVISIBLE (-150 3475);
FORCEADD OFFPAGE..1
(-700 4025);
FORCEPROP 2 LAST $XR0 21 
J 0
(-921 4025);
DISPLAY 0.638298 (-921 4025);
PAINT MONO (-921 4025);
FORCEPROP 2 LAST CDS_LIB mstr_standard
J 0
(-700 4025);
PAINT MONO (-700 4025);
DISPLAY INVISIBLE (-700 4025);
FORCEPROP 1 LAST OFFPAGE TRUE
J 0
(-375 3900);
PAINT GREEN (-375 3900);
DISPLAY INVISIBLE (-375 3900);
FORCEPROP 1 LAST COMMENT_BODY TRUE
J 0
(-575 3925);
DISPLAY 1.170213 (-575 3925);
PAINT GREEN (-575 3925);
DISPLAY INVISIBLE (-575 3925);
FORCEPROP 2 LAST PATH I44
J 0
(-875 4075);
DISPLAY 1.021277 (-875 4075);
PAINT ORANGE (-875 4075);
DISPLAY INVISIBLE (-875 4075);
FORCEADD PVDDQ_ABC..1
(2400 4600);
FORCEPROP 3 LASTPIN (2400 4550) SIG_NAME PVDDQ_ABC\g
J 0
(2410 4560);
DISPLAY 0.659574 (2410 4560);
PAINT MONO (2410 4560);
DISPLAY INVISIBLE (2410 4560);
FORCEPROP 1 LAST VOLTAGE 1.2V
J 0
(2355 4557);
DISPLAY 0.340426 (2355 4557);
PAINT SKYBLUE (2355 4557);
DISPLAY INVISIBLE (2355 4557);
FORCEPROP 2 LAST CDS_LIB mstr_symbols
J 0
(2400 4600);
PAINT ORANGE (2400 4600);
DISPLAY INVISIBLE (2400 4600);
FORCEPROP 1 LAST BODY_TYPE PLUMBING
J 0
(2355 4557);
DISPLAY 0.340426 (2355 4557);
PAINT GREEN (2355 4557);
DISPLAY INVISIBLE (2355 4557);
FORCEPROP 1 LAST PATH I45
J 0
(2450 4625);
DISPLAY 0.872340 (2450 4625);
PAINT AQUA (2450 4625);
DISPLAY INVISIBLE (2450 4625);
FORCEPROP 1 LAST HDL_POWER PVDDQ_ABC
J 1
(2400 4650);
DISPLAY 0.872340 (2400 4650);
PAINT GREEN (2400 4650);
DISPLAY INVISIBLE (2400 4650);
FORCEADD RES..2
R 2
(2400 4350);
FORCEPROP 1 LAST LOCATION R4G21
J 2
(2355 4475);
DISPLAY 0.617021 (2355 4475);
PAINT AQUA (2355 4475);
FORCEPROP 1 LAST PART_NUMBER G21796-026
J 2
(2360 4225);
DISPLAY 0.617021 (2360 4225);
PAINT BLUE (2360 4225);
FORCEPROP 1 LAST VALUE 1.00K
J 2
(2355 4425);
DISPLAY 0.617021 (2355 4425);
PAINT SKYBLUE (2355 4425);
FORCEPROP 1 LAST TOLERANCE 1%
J 2
(2355 4375);
DISPLAY 0.617021 (2355 4375);
PAINT SKYBLUE (2355 4375);
FORCEPROP 1 LAST PACK_TYPE 0402
J 2
(2360 4175);
DISPLAY 0.617021 (2360 4175);
PAINT SKYBLUE (2360 4175);
FORCEPROP 1 LAST MATERIAL CHIP
J 2
(2360 4275);
DISPLAY 0.617021 (2360 4275);
PAINT SKYBLUE (2360 4275);
FORCEPROP 1 LAST WATTAGE 1/16W
J 2
(2360 4325);
DISPLAY 0.617021 (2360 4325);
PAINT SKYBLUE (2360 4325);
FORCEPROP 1 LASTPIN (2400 4250) $PN 2
J 2
(2395 4260);
DISPLAY 0.617021 (2395 4260);
PAINT ORANGE (2395 4260);
FORCEPROP 1 LASTPIN (2400 4450) $PN 1
J 2
(2395 4412);
DISPLAY 0.617021 (2395 4412);
PAINT ORANGE (2395 4412);
FORCEPROP 2 LAST BOM_COST SM_CONTROLLER
J 2
(2400 4350);
PAINT MONO (2400 4350);
DISPLAY INVISIBLE (2400 4350);
FORCEPROP 2 LAST CDS_LIB mstr_discrete
J 0
(2400 4350);
PAINT ORANGE (2400 4350);
DISPLAY INVISIBLE (2400 4350);
FORCEPROP 2 LAST SEC_TYPE 0402
J 0
(2350 4575);
DISPLAY 1.021277 (2350 4575);
PAINT ORANGE (2350 4575);
DISPLAY INVISIBLE (2350 4575);
FORCEPROP 2 LAST SEC 1
J 0
(2350 4575);
DISPLAY 0.680851 (2350 4575);
PAINT MONO (2350 4575);
DISPLAY INVISIBLE (2350 4575);
FORCEPROP 2 LAST CDS_LOCATION R4G21
J 2
(2355 4475);
DISPLAY 0.617021 (2355 4475);
PAINT AQUA (2355 4475);
DISPLAY INVISIBLE (2355 4475);
FORCEPROP 1 LAST PATH I46
J 2
(2350 4525);
DISPLAY 0.978723 (2350 4525);
PAINT WHITE (2350 4525);
DISPLAY INVISIBLE (2350 4525);
FORCEPROP 2 LAST ROOM MEM
J 2
(2350 4525);
PAINT PEACH (2350 4525);
DISPLAY INVISIBLE (2350 4525);
FORCEADD OFFPAGE..2
(2825 4025);
FORCEPROP 2 LAST $XR0 47 
J 0
(3014 4025);
DISPLAY 0.638298 (3014 4025);
PAINT MONO (3014 4025);
FORCEPROP 2 LAST $XR1 48 
J 0
(3104 4025);
DISPLAY 0.638298 (3104 4025);
PAINT MONO (3104 4025);
FORCEPROP 2 LAST CDS_LIB mstr_standard
J 0
(2825 4025);
PAINT MONO (2825 4025);
DISPLAY INVISIBLE (2825 4025);
FORCEPROP 1 LAST OFFPAGE TRUE
J 0
(3150 3900);
PAINT GREEN (3150 3900);
DISPLAY INVISIBLE (3150 3900);
FORCEPROP 1 LAST COMMENT_BODY TRUE
J 0
(2780 3930);
DISPLAY 1.170213 (2780 3930);
PAINT GREEN (2780 3930);
DISPLAY INVISIBLE (2780 3930);
FORCEPROP 2 LAST PATH I47
J 0
(3000 4100);
DISPLAY 1.021277 (3000 4100);
PAINT ORANGE (3000 4100);
DISPLAY INVISIBLE (3000 4100);
FORCEADD RES..2
R 2
(2475 3700);
FORCEPROP 1 LAST LOCATION R4G22
J 2
(2430 3825);
DISPLAY 0.617021 (2430 3825);
PAINT AQUA (2430 3825);
FORCEPROP 1 LAST PART_NUMBER G21796-026
J 2
(2435 3575);
DISPLAY 0.617021 (2435 3575);
PAINT BLUE (2435 3575);
FORCEPROP 1 LAST VALUE 1.00K
J 2
(2430 3775);
DISPLAY 0.617021 (2430 3775);
PAINT SKYBLUE (2430 3775);
FORCEPROP 1 LAST TOLERANCE 1%
J 2
(2430 3725);
DISPLAY 0.617021 (2430 3725);
PAINT SKYBLUE (2430 3725);
FORCEPROP 1 LAST PACK_TYPE 0402
J 2
(2435 3525);
DISPLAY 0.617021 (2435 3525);
PAINT SKYBLUE (2435 3525);
FORCEPROP 1 LAST MATERIAL CHIP
J 2
(2435 3625);
DISPLAY 0.617021 (2435 3625);
PAINT SKYBLUE (2435 3625);
FORCEPROP 1 LAST WATTAGE 1/16W
J 2
(2435 3675);
DISPLAY 0.617021 (2435 3675);
PAINT SKYBLUE (2435 3675);
FORCEPROP 1 LASTPIN (2475 3600) $PN 2
J 2
(2470 3610);
DISPLAY 0.617021 (2470 3610);
PAINT ORANGE (2470 3610);
FORCEPROP 1 LASTPIN (2475 3800) $PN 1
J 2
(2470 3762);
DISPLAY 0.617021 (2470 3762);
PAINT ORANGE (2470 3762);
FORCEPROP 2 LAST CDS_LIB mstr_discrete
J 0
(2475 3700);
PAINT ORANGE (2475 3700);
DISPLAY INVISIBLE (2475 3700);
FORCEPROP 2 LAST BOM_COST PROC_SOCKET
J 2
(2475 3700);
PAINT MONO (2475 3700);
DISPLAY INVISIBLE (2475 3700);
FORCEPROP 2 LAST SEC_TYPE 0402
J 0
(2425 3925);
DISPLAY 1.021277 (2425 3925);
PAINT ORANGE (2425 3925);
DISPLAY INVISIBLE (2425 3925);
FORCEPROP 2 LAST SEC 1
J 0
(2425 3925);
DISPLAY 0.680851 (2425 3925);
PAINT MONO (2425 3925);
DISPLAY INVISIBLE (2425 3925);
FORCEPROP 2 LAST CDS_LOCATION R4G22
J 2
(2430 3825);
DISPLAY 0.617021 (2430 3825);
PAINT AQUA (2430 3825);
DISPLAY INVISIBLE (2430 3825);
FORCEPROP 1 LAST PATH I48
J 2
(2425 3875);
DISPLAY 0.978723 (2425 3875);
PAINT WHITE (2425 3875);
DISPLAY INVISIBLE (2425 3875);
FORCEPROP 2 LAST ROOM PROC
J 2
(2425 3875);
PAINT PEACH (2425 3875);
DISPLAY INVISIBLE (2425 3875);
FORCEADD GND..1
(2175 3375);
FORCEPROP 3 LASTPIN (2175 3425) SIG_NAME GND\g
J 0
(2185 3435);
DISPLAY 0.659574 (2185 3435);
PAINT MONO (2185 3435);
DISPLAY INVISIBLE (2185 3435);
FORCEPROP 1 LAST VOLTAGE 0
J 0
(2175 3375);
PAINT SKYBLUE (2175 3375);
DISPLAY INVISIBLE (2175 3375);
FORCEPROP 1 LAST SIZE 1B
J 0
(2250 3325);
DISPLAY 1.170213 (2250 3325);
PAINT GREEN (2250 3325);
DISPLAY INVISIBLE (2250 3325);
FORCEPROP 2 LAST CDS_LIB mstr_symbols
J 0
(2175 3375);
PAINT MONO (2175 3375);
DISPLAY INVISIBLE (2175 3375);
FORCEPROP 1 LAST BODY_TYPE PLUMBING
J 0
(2130 3332);
DISPLAY 0.340426 (2130 3332);
PAINT GREEN (2130 3332);
DISPLAY INVISIBLE (2130 3332);
FORCEPROP 1 LAST PATH I49
J 0
(2250 3375);
DISPLAY 0.872340 (2250 3375);
PAINT AQUA (2250 3375);
DISPLAY INVISIBLE (2250 3375);
FORCEPROP 1 LAST HDL_POWER GND
J 0
(2175 3525);
DISPLAY 1.170213 (2175 3525);
PAINT GREEN (2175 3525);
DISPLAY INVISIBLE (2175 3525);
FORCEADD RES..1
(-2025 4025);
FORCEPROP 1 LAST LOCATION R4F3
J 0
(-2050 4100);
DISPLAY 0.617021 (-2050 4100);
PAINT AQUA (-2050 4100);
FORCEPROP 1 LAST PART_NUMBER G21796-274
J 0
(-2150 3875);
DISPLAY 0.617021 (-2150 3875);
PAINT BLUE (-2150 3875);
FORCEPROP 1 LAST VALUE 2
J 2
(-2100 3975);
DISPLAY 0.617021 (-2100 3975);
PAINT SKYBLUE (-2100 3975);
FORCEPROP 1 LAST TOLERANCE 1.0%
J 0
(-1925 3925);
DISPLAY 0.617021 (-1925 3925);
PAINT SKYBLUE (-1925 3925);
FORCEPROP 1 LAST PACK_TYPE 0402
J 0
(-2150 3925);
DISPLAY 0.617021 (-2150 3925);
PAINT SKYBLUE (-2150 3925);
FORCEPROP 1 LAST MATERIAL CHIP
J 0
(-1800 3975);
DISPLAY 0.617021 (-1800 3975);
PAINT SKYBLUE (-1800 3975);
FORCEPROP 1 LAST WATTAGE 1/16W
J 2
(-1850 3975);
DISPLAY 0.617021 (-1850 3975);
PAINT SKYBLUE (-1850 3975);
FORCEPROP 1 LASTPIN (-1925 4025) $PN 2
J 0
(-1963 4037);
DISPLAY 0.617021 (-1963 4037);
PAINT MONO (-1963 4037);
FORCEPROP 1 LASTPIN (-2125 4025) $PN 1
J 0
(-2113 4037);
DISPLAY 0.617021 (-2113 4037);
PAINT MONO (-2113 4037);
FORCEPROP 2 LAST SEC_TYPE 0402
J 0
(-2075 4225);
PAINT MONO (-2075 4225);
DISPLAY INVISIBLE (-2075 4225);
FORCEPROP 2 LAST BOM_COST PROC_SOCKET
J 0
(-2025 4025);
PAINT MONO (-2025 4025);
DISPLAY INVISIBLE (-2025 4025);
FORCEPROP 2 LAST CDS_LIB mstr_discrete
J 0
(-2025 4025);
PAINT ORANGE (-2025 4025);
DISPLAY INVISIBLE (-2025 4025);
FORCEPROP 2 LAST SEC 1
J 0
(-2075 4225);
DISPLAY 0.936170 (-2075 4225);
PAINT MONO (-2075 4225);
DISPLAY INVISIBLE (-2075 4225);
FORCEPROP 2 LAST CDS_LOCATION R4F3
J 0
(-2050 4100);
DISPLAY 0.617021 (-2050 4100);
PAINT AQUA (-2050 4100);
DISPLAY INVISIBLE (-2050 4100);
FORCEPROP 1 LAST PATH I5
J 0
(-2075 4175);
DISPLAY 0.978723 (-2075 4175);
PAINT WHITE (-2075 4175);
DISPLAY INVISIBLE (-2075 4175);
FORCEPROP 0 LAST ROOM PROC
J 0
(-2100 3950);
DISPLAY 0.617021 (-2100 3950);
PAINT ORANGE (-2100 3950);
DISPLAY INVISIBLE (-2100 3950);
FORCEADD RES..1
(2175 4025);
FORCEPROP 1 LAST LOCATION R4G20
J 0
(2150 4100);
DISPLAY 0.617021 (2150 4100);
PAINT AQUA (2150 4100);
FORCEPROP 1 LAST PART_NUMBER G21796-274
J 0
(2050 3875);
DISPLAY 0.617021 (2050 3875);
PAINT BLUE (2050 3875);
FORCEPROP 1 LAST VALUE 2
J 2
(2100 3975);
DISPLAY 0.617021 (2100 3975);
PAINT SKYBLUE (2100 3975);
FORCEPROP 1 LAST TOLERANCE 1.0%
J 0
(2275 3925);
DISPLAY 0.617021 (2275 3925);
PAINT SKYBLUE (2275 3925);
FORCEPROP 1 LAST PACK_TYPE 0402
J 0
(2050 3925);
DISPLAY 0.617021 (2050 3925);
PAINT SKYBLUE (2050 3925);
FORCEPROP 1 LAST MATERIAL CHIP
J 0
(2400 3975);
DISPLAY 0.617021 (2400 3975);
PAINT SKYBLUE (2400 3975);
FORCEPROP 1 LAST WATTAGE 1/16W
J 2
(2350 3975);
DISPLAY 0.617021 (2350 3975);
PAINT SKYBLUE (2350 3975);
FORCEPROP 1 LASTPIN (2275 4025) $PN 2
J 0
(2237 4037);
DISPLAY 0.617021 (2237 4037);
PAINT MONO (2237 4037);
FORCEPROP 1 LASTPIN (2075 4025) $PN 1
J 0
(2087 4037);
DISPLAY 0.617021 (2087 4037);
PAINT MONO (2087 4037);
FORCEPROP 2 LAST CDS_LIB mstr_discrete
J 0
(2175 4025);
PAINT ORANGE (2175 4025);
DISPLAY INVISIBLE (2175 4025);
FORCEPROP 2 LAST BOM_COST PROC_SOCKET
J 0
(2175 4025);
PAINT MONO (2175 4025);
DISPLAY INVISIBLE (2175 4025);
FORCEPROP 2 LAST SEC_TYPE 0402
J 0
(2125 4225);
PAINT MONO (2125 4225);
DISPLAY INVISIBLE (2125 4225);
FORCEPROP 2 LAST SEC 1
J 0
(2125 4225);
DISPLAY 0.936170 (2125 4225);
PAINT MONO (2125 4225);
DISPLAY INVISIBLE (2125 4225);
FORCEPROP 2 LAST CDS_LOCATION R4G20
J 0
(2150 4100);
DISPLAY 0.617021 (2150 4100);
PAINT AQUA (2150 4100);
DISPLAY INVISIBLE (2150 4100);
FORCEPROP 1 LAST PATH I50
J 0
(2125 4175);
DISPLAY 0.978723 (2125 4175);
PAINT WHITE (2125 4175);
DISPLAY INVISIBLE (2125 4175);
FORCEPROP 0 LAST ROOM PROC
J 0
(2100 3950);
DISPLAY 0.617021 (2100 3950);
PAINT ORANGE (2100 3950);
DISPLAY INVISIBLE (2100 3950);
FORCEADD CAP_A..1
(1950 3725);
FORCEPROP 1 LAST LOCATION C4G17
J 0
(2000 3825);
DISPLAY 0.617021 (2000 3825);
PAINT AQUA (2000 3825);
FORCEPROP 1 LAST PART_NUMBER A36096-045
J 0
(2000 3575);
DISPLAY 0.617021 (2000 3575);
PAINT BLUE (2000 3575);
FORCEPROP 1 LAST VALUE 0.01UF
J 0
(2000 3775);
DISPLAY 0.617021 (2000 3775);
PAINT SKYBLUE (2000 3775);
FORCEPROP 1 LAST TOLERANCE 10%
J 0
(2000 3675);
DISPLAY 0.617021 (2000 3675);
PAINT SKYBLUE (2000 3675);
FORCEPROP 1 LAST PACK_TYPE 0402V
J 0
(2000 3525);
DISPLAY 0.617021 (2000 3525);
PAINT SKYBLUE (2000 3525);
FORCEPROP 1 LAST VOLTAGE 25V
J 0
(2000 3725);
DISPLAY 0.617021 (2000 3725);
PAINT SKYBLUE (2000 3725);
FORCEPROP 1 LAST MATERIAL X7R
J 0
(2000 3625);
DISPLAY 0.617021 (2000 3625);
PAINT SKYBLUE (2000 3625);
FORCEPROP 1 LASTPIN (1950 3825) $PN 1
J 0
(1960 3805);
DISPLAY 0.617021 (1960 3805);
PAINT ORANGE (1960 3805);
FORCEPROP 1 LASTPIN (1950 3625) $PN 2
J 0
(1960 3605);
DISPLAY 0.617021 (1960 3605);
PAINT ORANGE (1960 3605);
FORCEPROP 2 LAST CDS_LOCATION C4G17
J 0
(2000 3825);
DISPLAY 0.617021 (2000 3825);
PAINT AQUA (2000 3825);
DISPLAY INVISIBLE (2000 3825);
FORCEPROP 2 LAST BOM_COST SM_CONTROLLER
J 0
(1950 3725);
PAINT MONO (1950 3725);
DISPLAY INVISIBLE (1950 3725);
FORCEPROP 2 LAST CDS_LIB dev_discrete
J 0
(1950 3725);
PAINT ORANGE (1950 3725);
DISPLAY INVISIBLE (1950 3725);
FORCEPROP 2 LAST CDS_SEC 1
J 0
(2000 3875);
PAINT ORANGE (2000 3875);
DISPLAY INVISIBLE (2000 3875);
FORCEPROP 2 LAST SEC_TYPE 0402V
J 0
(2000 3925);
DISPLAY 1.021277 (2000 3925);
PAINT ORANGE (2000 3925);
DISPLAY INVISIBLE (2000 3925);
FORCEPROP 2 LAST SEC 1
J 0
(2000 3925);
DISPLAY 0.680851 (2000 3925);
PAINT MONO (2000 3925);
DISPLAY INVISIBLE (2000 3925);
FORCEPROP 1 LAST PATH I51
J 0
(2000 3875);
DISPLAY 0.978723 (2000 3875);
PAINT WHITE (2000 3875);
DISPLAY INVISIBLE (2000 3875);
FORCEPROP 0 LAST ROOM MEM
J 0
(2000 3475);
DISPLAY 0.978723 (2000 3475);
PAINT ORANGE (2000 3475);
DISPLAY INVISIBLE (2000 3475);
FORCEADD OFFPAGE..1
(1450 4025);
FORCEPROP 2 LAST $XR0 21 
J 0
(1229 4025);
DISPLAY 0.638298 (1229 4025);
PAINT MONO (1229 4025);
FORCEPROP 2 LAST CDS_LIB mstr_standard
J 0
(1450 4025);
PAINT MONO (1450 4025);
DISPLAY INVISIBLE (1450 4025);
FORCEPROP 1 LAST OFFPAGE TRUE
J 0
(1775 3900);
PAINT GREEN (1775 3900);
DISPLAY INVISIBLE (1775 3900);
FORCEPROP 1 LAST COMMENT_BODY TRUE
J 0
(1575 3925);
DISPLAY 1.170213 (1575 3925);
PAINT GREEN (1575 3925);
DISPLAY INVISIBLE (1575 3925);
FORCEPROP 2 LAST PATH I52
J 0
(1275 4075);
DISPLAY 1.021277 (1275 4075);
PAINT ORANGE (1275 4075);
DISPLAY INVISIBLE (1275 4075);
FORCEADD RES..2
R 2
(225 2675);
FORCEPROP 1 LAST LOCATION R6L13
J 2
(180 2800);
DISPLAY 0.617021 (180 2800);
PAINT AQUA (180 2800);
FORCEPROP 1 LAST PART_NUMBER G21796-026
J 2
(185 2550);
DISPLAY 0.617021 (185 2550);
PAINT BLUE (185 2550);
FORCEPROP 1 LAST VALUE 1.00K
J 2
(180 2750);
DISPLAY 0.617021 (180 2750);
PAINT SKYBLUE (180 2750);
FORCEPROP 1 LAST TOLERANCE 1%
J 2
(180 2700);
DISPLAY 0.617021 (180 2700);
PAINT SKYBLUE (180 2700);
FORCEPROP 1 LAST PACK_TYPE 0402
J 2
(185 2500);
DISPLAY 0.617021 (185 2500);
PAINT SKYBLUE (185 2500);
FORCEPROP 1 LAST MATERIAL CHIP
J 2
(185 2600);
DISPLAY 0.617021 (185 2600);
PAINT SKYBLUE (185 2600);
FORCEPROP 1 LAST WATTAGE 1/16W
J 2
(185 2650);
DISPLAY 0.617021 (185 2650);
PAINT SKYBLUE (185 2650);
FORCEPROP 1 LASTPIN (225 2575) $PN 2
J 2
(220 2585);
DISPLAY 0.617021 (220 2585);
PAINT ORANGE (220 2585);
FORCEPROP 1 LASTPIN (225 2775) $PN 1
J 2
(220 2737);
DISPLAY 0.617021 (220 2737);
PAINT ORANGE (220 2737);
FORCEPROP 2 LAST BOM_COST SM_CONTROLLER
J 2
(225 2675);
PAINT MONO (225 2675);
DISPLAY INVISIBLE (225 2675);
FORCEPROP 2 LAST CDS_LIB mstr_discrete
J 0
(225 2675);
PAINT ORANGE (225 2675);
DISPLAY INVISIBLE (225 2675);
FORCEPROP 2 LAST SEC_TYPE 0402
J 0
(175 2900);
DISPLAY 1.021277 (175 2900);
PAINT ORANGE (175 2900);
DISPLAY INVISIBLE (175 2900);
FORCEPROP 2 LAST SEC 1
J 0
(175 2900);
DISPLAY 0.680851 (175 2900);
PAINT MONO (175 2900);
DISPLAY INVISIBLE (175 2900);
FORCEPROP 2 LAST CDS_LOCATION R6L13
J 2
(180 2800);
DISPLAY 0.617021 (180 2800);
PAINT AQUA (180 2800);
DISPLAY INVISIBLE (180 2800);
FORCEPROP 1 LAST PATH I54
J 2
(175 2850);
DISPLAY 0.978723 (175 2850);
PAINT WHITE (175 2850);
DISPLAY INVISIBLE (175 2850);
FORCEPROP 2 LAST ROOM MEM
J 2
(175 2850);
PAINT PEACH (175 2850);
DISPLAY INVISIBLE (175 2850);
FORCEADD OFFPAGE..2
(650 2350);
FORCEPROP 2 LAST $XR0 51 
J 0
(839 2350);
DISPLAY 0.638298 (839 2350);
PAINT MONO (839 2350);
FORCEPROP 2 LAST $XR1 52 
J 0
(929 2350);
DISPLAY 0.638298 (929 2350);
PAINT MONO (929 2350);
FORCEPROP 2 LAST CDS_LIB mstr_standard
J 0
(650 2350);
PAINT MONO (650 2350);
DISPLAY INVISIBLE (650 2350);
FORCEPROP 1 LAST OFFPAGE TRUE
J 0
(975 2225);
PAINT GREEN (975 2225);
DISPLAY INVISIBLE (975 2225);
FORCEPROP 1 LAST COMMENT_BODY TRUE
J 0
(605 2255);
DISPLAY 1.170213 (605 2255);
PAINT GREEN (605 2255);
DISPLAY INVISIBLE (605 2255);
FORCEPROP 2 LAST PATH I55
J 0
(825 2425);
DISPLAY 1.021277 (825 2425);
PAINT ORANGE (825 2425);
DISPLAY INVISIBLE (825 2425);
FORCEADD RES..2
R 2
(300 2025);
FORCEPROP 1 LAST LOCATION R6L12
J 2
(255 2150);
DISPLAY 0.617021 (255 2150);
PAINT AQUA (255 2150);
FORCEPROP 1 LAST PART_NUMBER G21796-026
J 2
(260 1900);
DISPLAY 0.617021 (260 1900);
PAINT BLUE (260 1900);
FORCEPROP 1 LAST VALUE 1.00K
J 2
(255 2100);
DISPLAY 0.617021 (255 2100);
PAINT SKYBLUE (255 2100);
FORCEPROP 1 LAST TOLERANCE 1%
J 2
(255 2050);
DISPLAY 0.617021 (255 2050);
PAINT SKYBLUE (255 2050);
FORCEPROP 1 LAST PACK_TYPE 0402
J 2
(260 1850);
DISPLAY 0.617021 (260 1850);
PAINT SKYBLUE (260 1850);
FORCEPROP 1 LAST MATERIAL CHIP
J 2
(260 1950);
DISPLAY 0.617021 (260 1950);
PAINT SKYBLUE (260 1950);
FORCEPROP 1 LAST WATTAGE 1/16W
J 2
(260 2000);
DISPLAY 0.617021 (260 2000);
PAINT SKYBLUE (260 2000);
FORCEPROP 1 LASTPIN (300 1925) $PN 2
J 2
(295 1935);
DISPLAY 0.617021 (295 1935);
PAINT ORANGE (295 1935);
FORCEPROP 1 LASTPIN (300 2125) $PN 1
J 2
(295 2087);
DISPLAY 0.617021 (295 2087);
PAINT ORANGE (295 2087);
FORCEPROP 2 LAST CDS_LIB mstr_discrete
J 0
(300 2025);
PAINT ORANGE (300 2025);
DISPLAY INVISIBLE (300 2025);
FORCEPROP 2 LAST BOM_COST PROC_SOCKET
J 2
(300 2025);
PAINT MONO (300 2025);
DISPLAY INVISIBLE (300 2025);
FORCEPROP 2 LAST SEC_TYPE 0402
J 0
(250 2250);
DISPLAY 1.021277 (250 2250);
PAINT ORANGE (250 2250);
DISPLAY INVISIBLE (250 2250);
FORCEPROP 2 LAST SEC 1
J 0
(250 2250);
DISPLAY 0.680851 (250 2250);
PAINT MONO (250 2250);
DISPLAY INVISIBLE (250 2250);
FORCEPROP 2 LAST CDS_LOCATION R6L12
J 2
(255 2150);
DISPLAY 0.617021 (255 2150);
PAINT AQUA (255 2150);
DISPLAY INVISIBLE (255 2150);
FORCEPROP 1 LAST PATH I56
J 2
(250 2200);
DISPLAY 0.978723 (250 2200);
PAINT WHITE (250 2200);
DISPLAY INVISIBLE (250 2200);
FORCEPROP 2 LAST ROOM PROC
J 2
(250 2200);
PAINT PEACH (250 2200);
DISPLAY INVISIBLE (250 2200);
FORCEADD GND..1
(0 1700);
FORCEPROP 3 LASTPIN (0 1750) SIG_NAME GND\g
J 0
(10 1760);
DISPLAY 0.659574 (10 1760);
PAINT MONO (10 1760);
DISPLAY INVISIBLE (10 1760);
FORCEPROP 1 LAST VOLTAGE 0
J 0
(0 1700);
PAINT SKYBLUE (0 1700);
DISPLAY INVISIBLE (0 1700);
FORCEPROP 1 LAST SIZE 1B
J 0
(75 1650);
DISPLAY 1.170213 (75 1650);
PAINT GREEN (75 1650);
DISPLAY INVISIBLE (75 1650);
FORCEPROP 2 LAST CDS_LIB mstr_symbols
J 0
(0 1700);
PAINT MONO (0 1700);
DISPLAY INVISIBLE (0 1700);
FORCEPROP 1 LAST BODY_TYPE PLUMBING
J 0
(-45 1657);
DISPLAY 0.340426 (-45 1657);
PAINT GREEN (-45 1657);
DISPLAY INVISIBLE (-45 1657);
FORCEPROP 1 LAST PATH I57
J 0
(75 1700);
DISPLAY 0.872340 (75 1700);
PAINT AQUA (75 1700);
DISPLAY INVISIBLE (75 1700);
FORCEPROP 1 LAST HDL_POWER GND
J 0
(0 1850);
DISPLAY 1.170213 (0 1850);
PAINT GREEN (0 1850);
DISPLAY INVISIBLE (0 1850);
FORCEADD RES..1
(0 2350);
FORCEPROP 1 LAST LOCATION R6L14
J 0
(-25 2425);
DISPLAY 0.617021 (-25 2425);
PAINT AQUA (-25 2425);
FORCEPROP 1 LAST PART_NUMBER G21796-274
J 0
(-125 2200);
DISPLAY 0.617021 (-125 2200);
PAINT BLUE (-125 2200);
FORCEPROP 1 LAST VALUE 2
J 2
(-75 2300);
DISPLAY 0.617021 (-75 2300);
PAINT SKYBLUE (-75 2300);
FORCEPROP 1 LAST TOLERANCE 1.0%
J 0
(100 2250);
DISPLAY 0.617021 (100 2250);
PAINT SKYBLUE (100 2250);
FORCEPROP 1 LAST PACK_TYPE 0402
J 0
(-125 2250);
DISPLAY 0.617021 (-125 2250);
PAINT SKYBLUE (-125 2250);
FORCEPROP 1 LAST MATERIAL CHIP
J 0
(225 2300);
DISPLAY 0.617021 (225 2300);
PAINT SKYBLUE (225 2300);
FORCEPROP 1 LAST WATTAGE 1/16W
J 2
(175 2300);
DISPLAY 0.617021 (175 2300);
PAINT SKYBLUE (175 2300);
FORCEPROP 1 LASTPIN (100 2350) $PN 2
J 0
(62 2362);
DISPLAY 0.617021 (62 2362);
PAINT MONO (62 2362);
FORCEPROP 1 LASTPIN (-100 2350) $PN 1
J 0
(-88 2362);
DISPLAY 0.617021 (-88 2362);
PAINT MONO (-88 2362);
FORCEPROP 2 LAST CDS_LIB mstr_discrete
J 0
(0 2350);
PAINT ORANGE (0 2350);
DISPLAY INVISIBLE (0 2350);
FORCEPROP 2 LAST BOM_COST PROC_SOCKET
J 0
(0 2350);
PAINT MONO (0 2350);
DISPLAY INVISIBLE (0 2350);
FORCEPROP 2 LAST SEC_TYPE 0402
J 0
(-50 2550);
PAINT MONO (-50 2550);
DISPLAY INVISIBLE (-50 2550);
FORCEPROP 2 LAST SEC 1
J 0
(-50 2550);
DISPLAY 0.936170 (-50 2550);
PAINT MONO (-50 2550);
DISPLAY INVISIBLE (-50 2550);
FORCEPROP 2 LAST CDS_LOCATION R6L14
J 0
(-25 2425);
DISPLAY 0.617021 (-25 2425);
PAINT AQUA (-25 2425);
DISPLAY INVISIBLE (-25 2425);
FORCEPROP 1 LAST PATH I58
J 0
(-50 2500);
DISPLAY 0.978723 (-50 2500);
PAINT WHITE (-50 2500);
DISPLAY INVISIBLE (-50 2500);
FORCEPROP 0 LAST ROOM PROC
J 0
(-75 2275);
DISPLAY 0.617021 (-75 2275);
PAINT ORANGE (-75 2275);
DISPLAY INVISIBLE (-75 2275);
FORCEADD CAP_A..1
(-225 2050);
FORCEPROP 1 LAST LOCATION C6L7
J 0
(-175 2150);
DISPLAY 0.617021 (-175 2150);
PAINT AQUA (-175 2150);
FORCEPROP 1 LAST PART_NUMBER A36096-045
J 0
(-175 1900);
DISPLAY 0.617021 (-175 1900);
PAINT BLUE (-175 1900);
FORCEPROP 1 LAST VALUE 0.01UF
J 0
(-175 2100);
DISPLAY 0.617021 (-175 2100);
PAINT SKYBLUE (-175 2100);
FORCEPROP 1 LAST TOLERANCE 10%
J 0
(-175 2000);
DISPLAY 0.617021 (-175 2000);
PAINT SKYBLUE (-175 2000);
FORCEPROP 1 LAST PACK_TYPE 0402V
J 0
(-175 1850);
DISPLAY 0.617021 (-175 1850);
PAINT SKYBLUE (-175 1850);
FORCEPROP 1 LAST VOLTAGE 25V
J 0
(-175 2050);
DISPLAY 0.617021 (-175 2050);
PAINT SKYBLUE (-175 2050);
FORCEPROP 1 LAST MATERIAL X7R
J 0
(-175 1950);
DISPLAY 0.617021 (-175 1950);
PAINT SKYBLUE (-175 1950);
FORCEPROP 1 LASTPIN (-225 2150) $PN 1
J 0
(-215 2130);
DISPLAY 0.617021 (-215 2130);
PAINT ORANGE (-215 2130);
FORCEPROP 1 LASTPIN (-225 1950) $PN 2
J 0
(-215 1930);
DISPLAY 0.617021 (-215 1930);
PAINT ORANGE (-215 1930);
FORCEPROP 2 LAST CDS_LOCATION C6L7
J 0
(-175 2150);
DISPLAY 0.617021 (-175 2150);
PAINT AQUA (-175 2150);
DISPLAY INVISIBLE (-175 2150);
FORCEPROP 2 LAST BOM_COST SM_CONTROLLER
J 0
(-225 2050);
PAINT MONO (-225 2050);
DISPLAY INVISIBLE (-225 2050);
FORCEPROP 2 LAST CDS_LIB dev_discrete
J 0
(-225 2050);
PAINT ORANGE (-225 2050);
DISPLAY INVISIBLE (-225 2050);
FORCEPROP 2 LAST CDS_SEC 1
J 0
(-175 2200);
PAINT ORANGE (-175 2200);
DISPLAY INVISIBLE (-175 2200);
FORCEPROP 2 LAST SEC_TYPE 0402V
J 0
(-175 2250);
DISPLAY 1.021277 (-175 2250);
PAINT ORANGE (-175 2250);
DISPLAY INVISIBLE (-175 2250);
FORCEPROP 2 LAST SEC 1
J 0
(-175 2250);
DISPLAY 0.680851 (-175 2250);
PAINT MONO (-175 2250);
DISPLAY INVISIBLE (-175 2250);
FORCEPROP 1 LAST PATH I59
J 0
(-175 2200);
DISPLAY 0.978723 (-175 2200);
PAINT WHITE (-175 2200);
DISPLAY INVISIBLE (-175 2200);
FORCEPROP 0 LAST ROOM MEM
J 0
(-175 1800);
DISPLAY 0.978723 (-175 1800);
PAINT ORANGE (-175 1800);
DISPLAY INVISIBLE (-175 1800);
FORCEADD GND..1
(-2025 3375);
FORCEPROP 3 LASTPIN (-2025 3425) SIG_NAME GND\g
J 0
(-2015 3435);
DISPLAY 0.659574 (-2015 3435);
PAINT MONO (-2015 3435);
DISPLAY INVISIBLE (-2015 3435);
FORCEPROP 1 LAST VOLTAGE 0
J 0
(-2025 3375);
PAINT SKYBLUE (-2025 3375);
DISPLAY INVISIBLE (-2025 3375);
FORCEPROP 2 LAST CDS_LIB mstr_symbols
J 0
(-2025 3375);
PAINT MONO (-2025 3375);
DISPLAY INVISIBLE (-2025 3375);
FORCEPROP 1 LAST SIZE 1B
J 0
(-1950 3325);
DISPLAY 1.170213 (-1950 3325);
PAINT GREEN (-1950 3325);
DISPLAY INVISIBLE (-1950 3325);
FORCEPROP 1 LAST BODY_TYPE PLUMBING
J 0
(-2070 3332);
DISPLAY 0.340426 (-2070 3332);
PAINT GREEN (-2070 3332);
DISPLAY INVISIBLE (-2070 3332);
FORCEPROP 1 LAST PATH I6
J 0
(-1950 3375);
DISPLAY 0.872340 (-1950 3375);
PAINT AQUA (-1950 3375);
DISPLAY INVISIBLE (-1950 3375);
FORCEPROP 1 LAST HDL_POWER GND
J 0
(-2025 3525);
DISPLAY 1.170213 (-2025 3525);
PAINT GREEN (-2025 3525);
DISPLAY INVISIBLE (-2025 3525);
FORCEADD OFFPAGE..1
(-725 2350);
FORCEPROP 2 LAST $XR0 21 
J 0
(-946 2350);
DISPLAY 0.638298 (-946 2350);
PAINT MONO (-946 2350);
FORCEPROP 2 LAST CDS_LIB mstr_standard
J 0
(-725 2350);
PAINT MONO (-725 2350);
DISPLAY INVISIBLE (-725 2350);
FORCEPROP 1 LAST OFFPAGE TRUE
J 0
(-400 2225);
PAINT GREEN (-400 2225);
DISPLAY INVISIBLE (-400 2225);
FORCEPROP 1 LAST COMMENT_BODY TRUE
J 0
(-600 2250);
DISPLAY 1.170213 (-600 2250);
PAINT GREEN (-600 2250);
DISPLAY INVISIBLE (-600 2250);
FORCEPROP 2 LAST PATH I60
J 0
(-900 2400);
DISPLAY 1.021277 (-900 2400);
PAINT ORANGE (-900 2400);
DISPLAY INVISIBLE (-900 2400);
FORCEADD RES..2
R 2
(2400 2650);
FORCEPROP 1 LAST LOCATION R6L2
J 2
(2355 2775);
DISPLAY 0.617021 (2355 2775);
PAINT AQUA (2355 2775);
FORCEPROP 1 LAST PART_NUMBER G21796-026
J 2
(2360 2525);
DISPLAY 0.617021 (2360 2525);
PAINT BLUE (2360 2525);
FORCEPROP 1 LAST VALUE 1.00K
J 2
(2355 2725);
DISPLAY 0.617021 (2355 2725);
PAINT SKYBLUE (2355 2725);
FORCEPROP 1 LAST TOLERANCE 1%
J 2
(2355 2675);
DISPLAY 0.617021 (2355 2675);
PAINT SKYBLUE (2355 2675);
FORCEPROP 1 LAST PACK_TYPE 0402
J 2
(2360 2475);
DISPLAY 0.617021 (2360 2475);
PAINT SKYBLUE (2360 2475);
FORCEPROP 1 LAST MATERIAL CHIP
J 2
(2360 2575);
DISPLAY 0.617021 (2360 2575);
PAINT SKYBLUE (2360 2575);
FORCEPROP 1 LAST WATTAGE 1/16W
J 2
(2360 2625);
DISPLAY 0.617021 (2360 2625);
PAINT SKYBLUE (2360 2625);
FORCEPROP 1 LASTPIN (2400 2550) $PN 2
J 2
(2395 2560);
DISPLAY 0.617021 (2395 2560);
PAINT ORANGE (2395 2560);
FORCEPROP 1 LASTPIN (2400 2750) $PN 1
J 2
(2395 2712);
DISPLAY 0.617021 (2395 2712);
PAINT ORANGE (2395 2712);
FORCEPROP 2 LAST BOM_COST SM_CONTROLLER
J 2
(2400 2650);
PAINT MONO (2400 2650);
DISPLAY INVISIBLE (2400 2650);
FORCEPROP 2 LAST CDS_LIB mstr_discrete
J 0
(2400 2650);
PAINT ORANGE (2400 2650);
DISPLAY INVISIBLE (2400 2650);
FORCEPROP 2 LAST SEC_TYPE 0402
J 0
(2350 2875);
DISPLAY 1.021277 (2350 2875);
PAINT ORANGE (2350 2875);
DISPLAY INVISIBLE (2350 2875);
FORCEPROP 2 LAST SEC 1
J 0
(2350 2875);
DISPLAY 0.680851 (2350 2875);
PAINT MONO (2350 2875);
DISPLAY INVISIBLE (2350 2875);
FORCEPROP 2 LAST CDS_LOCATION R6L2
J 2
(2355 2775);
DISPLAY 0.617021 (2355 2775);
PAINT AQUA (2355 2775);
DISPLAY INVISIBLE (2355 2775);
FORCEPROP 1 LAST PATH I62
J 2
(2350 2825);
DISPLAY 0.978723 (2350 2825);
PAINT WHITE (2350 2825);
DISPLAY INVISIBLE (2350 2825);
FORCEPROP 2 LAST ROOM MEM
J 2
(2350 2825);
PAINT PEACH (2350 2825);
DISPLAY INVISIBLE (2350 2825);
FORCEADD OFFPAGE..2
(2825 2325);
FORCEPROP 2 LAST $XR0 53 
J 0
(3014 2325);
DISPLAY 0.638298 (3014 2325);
PAINT MONO (3014 2325);
FORCEPROP 2 LAST $XR1 54 
J 0
(3104 2325);
DISPLAY 0.638298 (3104 2325);
PAINT MONO (3104 2325);
FORCEPROP 2 LAST CDS_LIB mstr_standard
J 0
(2825 2325);
PAINT MONO (2825 2325);
DISPLAY INVISIBLE (2825 2325);
FORCEPROP 1 LAST OFFPAGE TRUE
J 0
(3150 2200);
PAINT GREEN (3150 2200);
DISPLAY INVISIBLE (3150 2200);
FORCEPROP 1 LAST COMMENT_BODY TRUE
J 0
(2780 2230);
DISPLAY 1.170213 (2780 2230);
PAINT GREEN (2780 2230);
DISPLAY INVISIBLE (2780 2230);
FORCEPROP 2 LAST PATH I63
J 0
(3000 2400);
DISPLAY 1.021277 (3000 2400);
PAINT ORANGE (3000 2400);
DISPLAY INVISIBLE (3000 2400);
FORCEADD RES..2
R 2
(2475 2000);
FORCEPROP 1 LAST LOCATION R6L1
J 2
(2430 2125);
DISPLAY 0.617021 (2430 2125);
PAINT AQUA (2430 2125);
FORCEPROP 1 LAST PART_NUMBER G21796-026
J 2
(2435 1875);
DISPLAY 0.617021 (2435 1875);
PAINT BLUE (2435 1875);
FORCEPROP 1 LAST VALUE 1.00K
J 2
(2430 2075);
DISPLAY 0.617021 (2430 2075);
PAINT SKYBLUE (2430 2075);
FORCEPROP 1 LAST TOLERANCE 1%
J 2
(2430 2025);
DISPLAY 0.617021 (2430 2025);
PAINT SKYBLUE (2430 2025);
FORCEPROP 1 LAST PACK_TYPE 0402
J 2
(2435 1825);
DISPLAY 0.617021 (2435 1825);
PAINT SKYBLUE (2435 1825);
FORCEPROP 1 LAST MATERIAL CHIP
J 2
(2435 1925);
DISPLAY 0.617021 (2435 1925);
PAINT SKYBLUE (2435 1925);
FORCEPROP 1 LAST WATTAGE 1/16W
J 2
(2435 1975);
DISPLAY 0.617021 (2435 1975);
PAINT SKYBLUE (2435 1975);
FORCEPROP 1 LASTPIN (2475 1900) $PN 2
J 2
(2470 1910);
DISPLAY 0.617021 (2470 1910);
PAINT ORANGE (2470 1910);
FORCEPROP 1 LASTPIN (2475 2100) $PN 1
J 2
(2470 2062);
DISPLAY 0.617021 (2470 2062);
PAINT ORANGE (2470 2062);
FORCEPROP 2 LAST CDS_LIB mstr_discrete
J 0
(2475 2000);
PAINT ORANGE (2475 2000);
DISPLAY INVISIBLE (2475 2000);
FORCEPROP 2 LAST BOM_COST PROC_SOCKET
J 2
(2475 2000);
PAINT MONO (2475 2000);
DISPLAY INVISIBLE (2475 2000);
FORCEPROP 2 LAST SEC_TYPE 0402
J 0
(2425 2225);
DISPLAY 1.021277 (2425 2225);
PAINT ORANGE (2425 2225);
DISPLAY INVISIBLE (2425 2225);
FORCEPROP 2 LAST SEC 1
J 0
(2425 2225);
DISPLAY 0.680851 (2425 2225);
PAINT MONO (2425 2225);
DISPLAY INVISIBLE (2425 2225);
FORCEPROP 2 LAST CDS_LOCATION R6L1
J 2
(2430 2125);
DISPLAY 0.617021 (2430 2125);
PAINT AQUA (2430 2125);
DISPLAY INVISIBLE (2430 2125);
FORCEPROP 1 LAST PATH I64
J 2
(2425 2175);
DISPLAY 0.978723 (2425 2175);
PAINT WHITE (2425 2175);
DISPLAY INVISIBLE (2425 2175);
FORCEPROP 2 LAST ROOM PROC
J 2
(2425 2175);
PAINT PEACH (2425 2175);
DISPLAY INVISIBLE (2425 2175);
FORCEADD GND..1
(2175 1675);
FORCEPROP 3 LASTPIN (2175 1725) SIG_NAME GND\g
J 0
(2185 1735);
DISPLAY 0.659574 (2185 1735);
PAINT MONO (2185 1735);
DISPLAY INVISIBLE (2185 1735);
FORCEPROP 1 LAST VOLTAGE 0
J 0
(2175 1675);
PAINT SKYBLUE (2175 1675);
DISPLAY INVISIBLE (2175 1675);
FORCEPROP 1 LAST SIZE 1B
J 0
(2250 1625);
DISPLAY 1.170213 (2250 1625);
PAINT GREEN (2250 1625);
DISPLAY INVISIBLE (2250 1625);
FORCEPROP 2 LAST CDS_LIB mstr_symbols
J 0
(2175 1675);
PAINT MONO (2175 1675);
DISPLAY INVISIBLE (2175 1675);
FORCEPROP 1 LAST BODY_TYPE PLUMBING
J 0
(2130 1632);
DISPLAY 0.340426 (2130 1632);
PAINT GREEN (2130 1632);
DISPLAY INVISIBLE (2130 1632);
FORCEPROP 1 LAST PATH I65
J 0
(2250 1675);
DISPLAY 0.872340 (2250 1675);
PAINT AQUA (2250 1675);
DISPLAY INVISIBLE (2250 1675);
FORCEPROP 1 LAST HDL_POWER GND
J 0
(2175 1825);
DISPLAY 1.170213 (2175 1825);
PAINT GREEN (2175 1825);
DISPLAY INVISIBLE (2175 1825);
FORCEADD RES..1
(2175 2325);
FORCEPROP 1 LAST LOCATION R6L3
J 0
(2150 2400);
DISPLAY 0.617021 (2150 2400);
PAINT AQUA (2150 2400);
FORCEPROP 1 LAST PART_NUMBER G21796-274
J 0
(2050 2175);
DISPLAY 0.617021 (2050 2175);
PAINT BLUE (2050 2175);
FORCEPROP 1 LAST VALUE 2
J 2
(2100 2275);
DISPLAY 0.617021 (2100 2275);
PAINT SKYBLUE (2100 2275);
FORCEPROP 1 LAST TOLERANCE 1.0%
J 0
(2275 2225);
DISPLAY 0.617021 (2275 2225);
PAINT SKYBLUE (2275 2225);
FORCEPROP 1 LAST PACK_TYPE 0402
J 0
(2050 2225);
DISPLAY 0.617021 (2050 2225);
PAINT SKYBLUE (2050 2225);
FORCEPROP 1 LAST MATERIAL CHIP
J 0
(2400 2275);
DISPLAY 0.617021 (2400 2275);
PAINT SKYBLUE (2400 2275);
FORCEPROP 1 LAST WATTAGE 1/16W
J 2
(2350 2275);
DISPLAY 0.617021 (2350 2275);
PAINT SKYBLUE (2350 2275);
FORCEPROP 1 LASTPIN (2275 2325) $PN 2
J 0
(2237 2337);
DISPLAY 0.617021 (2237 2337);
PAINT MONO (2237 2337);
FORCEPROP 1 LASTPIN (2075 2325) $PN 1
J 0
(2087 2337);
DISPLAY 0.617021 (2087 2337);
PAINT MONO (2087 2337);
FORCEPROP 2 LAST CDS_LIB mstr_discrete
J 0
(2175 2325);
PAINT ORANGE (2175 2325);
DISPLAY INVISIBLE (2175 2325);
FORCEPROP 2 LAST BOM_COST PROC_SOCKET
J 0
(2175 2325);
PAINT MONO (2175 2325);
DISPLAY INVISIBLE (2175 2325);
FORCEPROP 2 LAST SEC_TYPE 0402
J 0
(2125 2525);
PAINT MONO (2125 2525);
DISPLAY INVISIBLE (2125 2525);
FORCEPROP 2 LAST SEC 1
J 0
(2125 2525);
DISPLAY 0.936170 (2125 2525);
PAINT MONO (2125 2525);
DISPLAY INVISIBLE (2125 2525);
FORCEPROP 2 LAST CDS_LOCATION R6L3
J 0
(2150 2400);
DISPLAY 0.617021 (2150 2400);
PAINT AQUA (2150 2400);
DISPLAY INVISIBLE (2150 2400);
FORCEPROP 1 LAST PATH I66
J 0
(2125 2475);
DISPLAY 0.978723 (2125 2475);
PAINT WHITE (2125 2475);
DISPLAY INVISIBLE (2125 2475);
FORCEPROP 0 LAST ROOM PROC
J 0
(2100 2250);
DISPLAY 0.617021 (2100 2250);
PAINT ORANGE (2100 2250);
DISPLAY INVISIBLE (2100 2250);
FORCEADD CAP_A..1
(1950 2025);
FORCEPROP 1 LAST LOCATION C6L2
J 0
(2000 2125);
DISPLAY 0.617021 (2000 2125);
PAINT AQUA (2000 2125);
FORCEPROP 1 LAST PART_NUMBER A36096-045
J 0
(2000 1875);
DISPLAY 0.617021 (2000 1875);
PAINT BLUE (2000 1875);
FORCEPROP 1 LAST VALUE 0.01UF
J 0
(2000 2075);
DISPLAY 0.617021 (2000 2075);
PAINT SKYBLUE (2000 2075);
FORCEPROP 1 LAST TOLERANCE 10%
J 0
(2000 1975);
DISPLAY 0.617021 (2000 1975);
PAINT SKYBLUE (2000 1975);
FORCEPROP 1 LAST PACK_TYPE 0402V
J 0
(2000 1825);
DISPLAY 0.617021 (2000 1825);
PAINT SKYBLUE (2000 1825);
FORCEPROP 1 LAST VOLTAGE 25V
J 0
(2000 2025);
DISPLAY 0.617021 (2000 2025);
PAINT SKYBLUE (2000 2025);
FORCEPROP 1 LAST MATERIAL X7R
J 0
(2000 1925);
DISPLAY 0.617021 (2000 1925);
PAINT SKYBLUE (2000 1925);
FORCEPROP 1 LASTPIN (1950 2125) $PN 1
J 0
(1960 2105);
DISPLAY 0.617021 (1960 2105);
PAINT ORANGE (1960 2105);
FORCEPROP 1 LASTPIN (1950 1925) $PN 2
J 0
(1960 1905);
DISPLAY 0.617021 (1960 1905);
PAINT ORANGE (1960 1905);
FORCEPROP 2 LAST CDS_LOCATION C6L2
J 0
(2000 2125);
DISPLAY 0.617021 (2000 2125);
PAINT AQUA (2000 2125);
DISPLAY INVISIBLE (2000 2125);
FORCEPROP 2 LAST BOM_COST SM_CONTROLLER
J 0
(1950 2025);
PAINT MONO (1950 2025);
DISPLAY INVISIBLE (1950 2025);
FORCEPROP 2 LAST CDS_LIB dev_discrete
J 0
(1950 2025);
PAINT ORANGE (1950 2025);
DISPLAY INVISIBLE (1950 2025);
FORCEPROP 2 LAST CDS_SEC 1
J 0
(2000 2175);
PAINT ORANGE (2000 2175);
DISPLAY INVISIBLE (2000 2175);
FORCEPROP 2 LAST SEC_TYPE 0402V
J 0
(2000 2225);
DISPLAY 1.021277 (2000 2225);
PAINT ORANGE (2000 2225);
DISPLAY INVISIBLE (2000 2225);
FORCEPROP 2 LAST SEC 1
J 0
(2000 2225);
DISPLAY 0.680851 (2000 2225);
PAINT MONO (2000 2225);
DISPLAY INVISIBLE (2000 2225);
FORCEPROP 1 LAST PATH I67
J 0
(2000 2175);
DISPLAY 0.978723 (2000 2175);
PAINT WHITE (2000 2175);
DISPLAY INVISIBLE (2000 2175);
FORCEPROP 0 LAST ROOM MEM
J 0
(2000 1775);
DISPLAY 0.978723 (2000 1775);
PAINT ORANGE (2000 1775);
DISPLAY INVISIBLE (2000 1775);
FORCEADD OFFPAGE..1
(1450 2325);
FORCEPROP 2 LAST $XR0 21 
J 0
(1229 2325);
DISPLAY 0.638298 (1229 2325);
PAINT MONO (1229 2325);
FORCEPROP 2 LAST CDS_LIB mstr_standard
J 0
(1450 2325);
PAINT MONO (1450 2325);
DISPLAY INVISIBLE (1450 2325);
FORCEPROP 1 LAST OFFPAGE TRUE
J 0
(1775 2200);
PAINT GREEN (1775 2200);
DISPLAY INVISIBLE (1775 2200);
FORCEPROP 1 LAST COMMENT_BODY TRUE
J 0
(1575 2225);
DISPLAY 1.170213 (1575 2225);
PAINT GREEN (1575 2225);
DISPLAY INVISIBLE (1575 2225);
FORCEPROP 2 LAST PATH I68
J 0
(1275 2375);
DISPLAY 1.021277 (1275 2375);
PAINT ORANGE (1275 2375);
DISPLAY INVISIBLE (1275 2375);
FORCEADD PVDDQ_DEF..1
(225 2925);
FORCEPROP 3 LASTPIN (225 2875) SIG_NAME PVDDQ_DEF\g
J 0
(235 2885);
DISPLAY 0.659574 (235 2885);
PAINT MONO (235 2885);
DISPLAY INVISIBLE (235 2885);
FORCEPROP 1 LAST VOLTAGE 1.2V
J 0
(180 2882);
DISPLAY 0.340426 (180 2882);
PAINT SKYBLUE (180 2882);
DISPLAY INVISIBLE (180 2882);
FORCEPROP 2 LAST CDS_LIB mstr_symbols
J 0
(225 2925);
PAINT ORANGE (225 2925);
DISPLAY INVISIBLE (225 2925);
FORCEPROP 1 LAST BODY_TYPE PLUMBING
J 0
(180 2882);
DISPLAY 0.340426 (180 2882);
PAINT GREEN (180 2882);
DISPLAY INVISIBLE (180 2882);
FORCEPROP 1 LAST PATH I69
J 0
(275 2950);
DISPLAY 0.872340 (275 2950);
PAINT AQUA (275 2950);
DISPLAY INVISIBLE (275 2950);
FORCEPROP 1 LAST HDL_POWER PVDDQ_DEF
J 1
(225 2975);
DISPLAY 0.872340 (225 2975);
PAINT GREEN (225 2975);
DISPLAY INVISIBLE (225 2975);
FORCEADD CAP_A..1
(-2250 3725);
FORCEPROP 1 LAST LOCATION C4F9
J 0
(-2200 3825);
DISPLAY 0.617021 (-2200 3825);
PAINT AQUA (-2200 3825);
FORCEPROP 1 LAST PART_NUMBER A36096-045
J 0
(-2200 3575);
DISPLAY 0.617021 (-2200 3575);
PAINT BLUE (-2200 3575);
FORCEPROP 1 LAST VALUE 0.01UF
J 0
(-2200 3775);
DISPLAY 0.617021 (-2200 3775);
PAINT SKYBLUE (-2200 3775);
FORCEPROP 1 LAST TOLERANCE 10%
J 0
(-2200 3675);
DISPLAY 0.617021 (-2200 3675);
PAINT SKYBLUE (-2200 3675);
FORCEPROP 1 LAST PACK_TYPE 0402V
J 0
(-2200 3525);
DISPLAY 0.617021 (-2200 3525);
PAINT SKYBLUE (-2200 3525);
FORCEPROP 1 LAST VOLTAGE 25V
J 0
(-2200 3725);
DISPLAY 0.617021 (-2200 3725);
PAINT SKYBLUE (-2200 3725);
FORCEPROP 1 LAST MATERIAL X7R
J 0
(-2200 3625);
DISPLAY 0.617021 (-2200 3625);
PAINT SKYBLUE (-2200 3625);
FORCEPROP 1 LASTPIN (-2250 3825) $PN 1
J 0
(-2240 3805);
DISPLAY 0.617021 (-2240 3805);
PAINT ORANGE (-2240 3805);
FORCEPROP 1 LASTPIN (-2250 3625) $PN 2
J 0
(-2240 3605);
DISPLAY 0.617021 (-2240 3605);
PAINT ORANGE (-2240 3605);
FORCEPROP 2 LAST CDS_LOCATION C4F9
J 0
(-2200 3825);
DISPLAY 0.617021 (-2200 3825);
PAINT AQUA (-2200 3825);
DISPLAY INVISIBLE (-2200 3825);
FORCEPROP 2 LAST BOM_COST SM_CONTROLLER
J 0
(-2250 3725);
PAINT MONO (-2250 3725);
DISPLAY INVISIBLE (-2250 3725);
FORCEPROP 2 LAST CDS_LIB dev_discrete
J 0
(-2250 3725);
PAINT ORANGE (-2250 3725);
DISPLAY INVISIBLE (-2250 3725);
FORCEPROP 2 LAST CDS_SEC 1
J 0
(-2200 3875);
PAINT ORANGE (-2200 3875);
DISPLAY INVISIBLE (-2200 3875);
FORCEPROP 2 LAST SEC_TYPE 0402V
J 0
(-2200 3925);
DISPLAY 1.021277 (-2200 3925);
PAINT ORANGE (-2200 3925);
DISPLAY INVISIBLE (-2200 3925);
FORCEPROP 2 LAST SEC 1
J 0
(-2200 3925);
DISPLAY 0.680851 (-2200 3925);
PAINT MONO (-2200 3925);
DISPLAY INVISIBLE (-2200 3925);
FORCEPROP 1 LAST PATH I7
J 0
(-2200 3875);
DISPLAY 0.978723 (-2200 3875);
PAINT WHITE (-2200 3875);
DISPLAY INVISIBLE (-2200 3875);
FORCEPROP 0 LAST ROOM MEM
J 0
(-2200 3475);
DISPLAY 0.978723 (-2200 3475);
PAINT ORANGE (-2200 3475);
DISPLAY INVISIBLE (-2200 3475);
FORCEADD PVDDQ_DEF..1
(2400 2900);
FORCEPROP 3 LASTPIN (2400 2850) SIG_NAME PVDDQ_DEF\g
J 0
(2410 2860);
DISPLAY 0.659574 (2410 2860);
PAINT MONO (2410 2860);
DISPLAY INVISIBLE (2410 2860);
FORCEPROP 1 LAST VOLTAGE 1.2V
J 0
(2355 2857);
DISPLAY 0.340426 (2355 2857);
PAINT SKYBLUE (2355 2857);
DISPLAY INVISIBLE (2355 2857);
FORCEPROP 2 LAST CDS_LIB mstr_symbols
J 0
(2400 2900);
PAINT ORANGE (2400 2900);
DISPLAY INVISIBLE (2400 2900);
FORCEPROP 1 LAST BODY_TYPE PLUMBING
J 0
(2355 2857);
DISPLAY 0.340426 (2355 2857);
PAINT GREEN (2355 2857);
DISPLAY INVISIBLE (2355 2857);
FORCEPROP 1 LAST PATH I70
J 0
(2450 2925);
DISPLAY 0.872340 (2450 2925);
PAINT AQUA (2450 2925);
DISPLAY INVISIBLE (2450 2925);
FORCEPROP 1 LAST HDL_POWER PVDDQ_DEF
J 1
(2400 2950);
DISPLAY 0.872340 (2400 2950);
PAINT GREEN (2400 2950);
DISPLAY INVISIBLE (2400 2950);
FORCEADD OFFPAGE..1
(-2750 4025);
FORCEPROP 2 LAST $XR0 21 
J 0
(-2971 4025);
DISPLAY 0.638298 (-2971 4025);
PAINT MONO (-2971 4025);
FORCEPROP 2 LAST CDS_LIB mstr_standard
J 0
(-2750 4025);
PAINT MONO (-2750 4025);
DISPLAY INVISIBLE (-2750 4025);
FORCEPROP 1 LAST OFFPAGE TRUE
J 0
(-2425 3900);
PAINT GREEN (-2425 3900);
DISPLAY INVISIBLE (-2425 3900);
FORCEPROP 1 LAST COMMENT_BODY TRUE
J 0
(-2625 3925);
DISPLAY 1.170213 (-2625 3925);
PAINT GREEN (-2625 3925);
DISPLAY INVISIBLE (-2625 3925);
FORCEPROP 2 LAST PATH I8
J 0
(-3000 4075);
DISPLAY 1.021277 (-3000 4075);
PAINT ORANGE (-3000 4075);
DISPLAY INVISIBLE (-3000 4075);
FORCEADD RES..2
R 2
(-1800 2675);
FORCEPROP 1 LAST LOCATION R6M1
J 2
(-1845 2800);
DISPLAY 0.617021 (-1845 2800);
PAINT AQUA (-1845 2800);
FORCEPROP 1 LAST PART_NUMBER G21796-026
J 2
(-1840 2550);
DISPLAY 0.617021 (-1840 2550);
PAINT BLUE (-1840 2550);
FORCEPROP 1 LAST VALUE 1.00K
J 2
(-1845 2750);
DISPLAY 0.617021 (-1845 2750);
PAINT SKYBLUE (-1845 2750);
FORCEPROP 1 LAST TOLERANCE 1%
J 2
(-1845 2700);
DISPLAY 0.617021 (-1845 2700);
PAINT SKYBLUE (-1845 2700);
FORCEPROP 1 LAST PACK_TYPE 0402
J 2
(-1840 2500);
DISPLAY 0.617021 (-1840 2500);
PAINT SKYBLUE (-1840 2500);
FORCEPROP 1 LAST MATERIAL CHIP
J 2
(-1840 2600);
DISPLAY 0.617021 (-1840 2600);
PAINT SKYBLUE (-1840 2600);
FORCEPROP 1 LAST WATTAGE 1/16W
J 2
(-1840 2650);
DISPLAY 0.617021 (-1840 2650);
PAINT SKYBLUE (-1840 2650);
FORCEPROP 1 LASTPIN (-1800 2575) $PN 2
J 2
(-1805 2585);
DISPLAY 0.617021 (-1805 2585);
PAINT ORANGE (-1805 2585);
FORCEPROP 1 LASTPIN (-1800 2775) $PN 1
J 2
(-1805 2737);
DISPLAY 0.617021 (-1805 2737);
PAINT ORANGE (-1805 2737);
FORCEPROP 2 LAST CDS_LIB mstr_discrete
J 0
(-1800 2675);
PAINT ORANGE (-1800 2675);
DISPLAY INVISIBLE (-1800 2675);
FORCEPROP 2 LAST BOM_COST PROC_SOCKET
J 2
(-1800 2675);
PAINT MONO (-1800 2675);
DISPLAY INVISIBLE (-1800 2675);
FORCEPROP 2 LAST SEC_TYPE 0402
J 0
(-1850 2900);
DISPLAY 1.021277 (-1850 2900);
PAINT ORANGE (-1850 2900);
DISPLAY INVISIBLE (-1850 2900);
FORCEPROP 2 LAST SEC 1
J 0
(-1850 2900);
DISPLAY 0.680851 (-1850 2900);
PAINT MONO (-1850 2900);
DISPLAY INVISIBLE (-1850 2900);
FORCEPROP 2 LAST CDS_LOCATION R6M1
J 2
(-1845 2800);
DISPLAY 0.617021 (-1845 2800);
PAINT AQUA (-1845 2800);
DISPLAY INVISIBLE (-1845 2800);
FORCEPROP 1 LAST PATH I9
J 2
(-1850 2850);
DISPLAY 0.978723 (-1850 2850);
PAINT WHITE (-1850 2850);
DISPLAY INVISIBLE (-1850 2850);
FORCEPROP 2 LAST ROOM MEM
J 2
(-1850 2850);
PAINT PEACH (-1850 2850);
DISPLAY INVISIBLE (-1850 2850);
FORCEADD CAD_NOTE..1
(-1050 3200);
FORCEPROP 0 LAST L1 PLACE BETWEEN DIMM_E1 & E2
J 0
(-1200 3075);
PAINT WHITE (-1200 3075);
FORCEPROP 2 LAST BOM_COST SM_CONTROLLER
J 0
(-1200 3150);
PAINT WHITE (-1200 3150);
DISPLAY INVISIBLE (-1200 3150);
FORCEPROP 2 LAST CDS_LIB mstr_symbols
J 0
(-1050 3200);
PAINT WHITE (-1050 3200);
DISPLAY INVISIBLE (-1050 3200);
FORCEPROP 1 LAST COMMENT_BODY TRUE
J 0
(-1025 3300);
DISPLAY 1.319149 (-1025 3300);
PAINT WHITE (-1025 3300);
DISPLAY INVISIBLE (-1025 3300);
FORCEPROP 2 LAST ROOM BMC
J 0
(-1200 3150);
PAINT WHITE (-1200 3150);
DISPLAY INVISIBLE (-1200 3150);
FORCEADD CAD_NOTE..1
(-3075 3200);
FORCEPROP 0 LAST L1 PLACE BETWEEN DIMM_D1 & D2
J 0
(-3225 3075);
PAINT WHITE (-3225 3075);
FORCEPROP 2 LAST BOM_COST SM_CONTROLLER
J 0
(-3225 3150);
PAINT WHITE (-3225 3150);
DISPLAY INVISIBLE (-3225 3150);
FORCEPROP 2 LAST CDS_LIB mstr_symbols
J 0
(-3075 3200);
PAINT WHITE (-3075 3200);
DISPLAY INVISIBLE (-3075 3200);
FORCEPROP 1 LAST COMMENT_BODY TRUE
J 0
(-3050 3300);
DISPLAY 1.319149 (-3050 3300);
PAINT WHITE (-3050 3300);
DISPLAY INVISIBLE (-3050 3300);
FORCEPROP 2 LAST ROOM BMC
J 0
(-3225 3150);
PAINT WHITE (-3225 3150);
DISPLAY INVISIBLE (-3225 3150);
FORCEADD CAD_NOTE..1
(1125 4875);
FORCEPROP 0 LAST L1 PLACE BETWEEN DIMM_C1 & C2
J 0
(975 4725);
PAINT WHITE (975 4725);
FORCEPROP 2 LAST BOM_COST SM_CONTROLLER
J 0
(975 4825);
PAINT WHITE (975 4825);
DISPLAY INVISIBLE (975 4825);
FORCEPROP 2 LAST CDS_LIB mstr_symbols
J 0
(1125 4875);
PAINT WHITE (1125 4875);
DISPLAY INVISIBLE (1125 4875);
FORCEPROP 1 LAST COMMENT_BODY TRUE
J 0
(1150 4975);
DISPLAY 1.319149 (1150 4975);
PAINT WHITE (1150 4975);
DISPLAY INVISIBLE (1150 4975);
FORCEPROP 2 LAST ROOM BMC
J 0
(975 4825);
PAINT WHITE (975 4825);
DISPLAY INVISIBLE (975 4825);
FORCEADD CAD_NOTE..1
(1125 3175);
FORCEPROP 0 LAST L1 PLACE BETWEEN DIMM_F1 & F2
J 0
(975 3050);
PAINT WHITE (975 3050);
FORCEPROP 2 LAST BOM_COST SM_CONTROLLER
J 0
(975 3125);
PAINT WHITE (975 3125);
DISPLAY INVISIBLE (975 3125);
FORCEPROP 2 LAST CDS_LIB mstr_symbols
J 0
(1125 3175);
PAINT WHITE (1125 3175);
DISPLAY INVISIBLE (1125 3175);
FORCEPROP 1 LAST COMMENT_BODY TRUE
J 0
(1150 3275);
DISPLAY 1.319149 (1150 3275);
PAINT WHITE (1150 3275);
DISPLAY INVISIBLE (1150 3275);
FORCEPROP 2 LAST ROOM BMC
J 0
(975 3125);
PAINT WHITE (975 3125);
DISPLAY INVISIBLE (975 3125);
FORCEADD CAD_NOTE..1
(-1025 4875);
FORCEPROP 0 LAST L1 PLACE BETWEEN DIMM_B1 & B2
J 0
(-1175 4750);
PAINT WHITE (-1175 4750);
FORCEPROP 2 LAST BOM_COST SM_CONTROLLER
J 0
(-1175 4825);
PAINT WHITE (-1175 4825);
DISPLAY INVISIBLE (-1175 4825);
FORCEPROP 2 LAST CDS_LIB mstr_symbols
J 0
(-1025 4875);
PAINT WHITE (-1025 4875);
DISPLAY INVISIBLE (-1025 4875);
FORCEPROP 1 LAST COMMENT_BODY TRUE
J 0
(-1000 4975);
DISPLAY 1.319149 (-1000 4975);
PAINT WHITE (-1000 4975);
DISPLAY INVISIBLE (-1000 4975);
FORCEPROP 2 LAST ROOM BMC
J 0
(-1175 4825);
PAINT WHITE (-1175 4825);
DISPLAY INVISIBLE (-1175 4825);
FORCEADD CAD_NOTE..1
(-3075 4875);
FORCEPROP 0 LAST L1 PLACE BETWEEN DIMM_A1 & A2
J 0
(-3225 4750);
PAINT WHITE (-3225 4750);
FORCEPROP 2 LAST CDS_LIB mstr_symbols
J 0
(-3075 4875);
PAINT WHITE (-3075 4875);
DISPLAY INVISIBLE (-3075 4875);
FORCEPROP 2 LAST BOM_COST SM_CONTROLLER
J 0
(-3225 4825);
PAINT WHITE (-3225 4825);
DISPLAY INVISIBLE (-3225 4825);
FORCEPROP 1 LAST COMMENT_BODY TRUE
J 0
(-3050 4975);
DISPLAY 1.319149 (-3050 4975);
PAINT WHITE (-3050 4975);
DISPLAY INVISIBLE (-3050 4975);
FORCEPROP 2 LAST ROOM BMC
J 0
(-3225 4825);
PAINT WHITE (-3225 4825);
DISPLAY INVISIBLE (-3225 4825);
FORCEADD INTEL_CORP_BPAGE..1
(4025 625);
FORCEPROP 1 LAST CDS_CON_LAST_MODIFIED Tue Dec 01 11:51:49 2015
J 0
(2600 950);
PAINT ORANGE (2600 950);
DISPLAY INVISIBLE (2600 950);
FORCEPROP 1 LAST CUSTOM_TXT_CDS <CURRENT_DESIGN_SHEET> OF <TOTAL_DESIGN_SHEETS>
J 0
(3525 650);
PAINT GREEN (3525 650);
FORCEPROP 1 LAST CUSTOM_TXT_CDS <CON_LAST_MODIFIED>
J 0
(2100 975);
PAINT GREEN (2100 975);
FORCEPROP 2 LAST CUSTOM_TXT_CDS <XR_PAGE_TITLE>
J 0
(-3865 5875);
DISPLAY 0.638298 (-3865 5875);
PAINT PINK (-3865 5875);
DISPLAY INVISIBLE (-3865 5875);
FORCEPROP 1 LAST SCH_ADDRESS3 Santa Clara, CA 95052-8119
J 0
(50 650);
DISPLAY 0.617021 (50 650);
PAINT GREEN (50 650);
FORCEPROP 1 LAST SCH_ADDRESS2 P.O. BOX 58119
J 0
(50 700);
DISPLAY 0.617021 (50 700);
PAINT GREEN (50 700);
FORCEPROP 1 LAST SCH_ADDRESS1 2200 Mission College Blvd.
J 0
(50 750);
DISPLAY 0.617021 (50 750);
PAINT GREEN (50 750);
FORCEPROP 1 LAST SCH_TITLE CPU SIDE BAND:CPU0 DIMM CA VREF
J 0
(-3925 675);
DISPLAY 1.212766 (-3925 675);
PAINT ORANGE (-3925 675);
FORCEPROP 1 LAST SCH_NUMBER H4694802
J 0
(2725 775);
DISPLAY 1.212766 (2725 775);
PAINT YELLOW (2725 775);
FORCEPROP 1 LAST SCH_DEPT BESD
J 1
(-425 725);
DISPLAY 1.212766 (-425 725);
PAINT YELLOW (-425 725);
FORCEPROP 1 LAST SCH_REV 2.420
J 0
(3775 775);
DISPLAY 0.978723 (3775 775);
PAINT YELLOW (3775 775);
FORCEPROP 2 LAST CDS_LIB mstr_symbols
J 0
(4025 625);
PAINT MONO (4025 625);
DISPLAY INVISIBLE (4025 625);
FORCEPROP 2 LAST PAGE_BORDER TRUE
J 0
(-3865 5875);
DISPLAY 0.638298 (-3865 5875);
PAINT PINK (-3865 5875);
DISPLAY INVISIBLE (-3865 5875);
FORCEPROP 1 LAST COMMENT_BODY TRUE
J 0
(4037 637);
DISPLAY 0.468085 (4037 637);
PAINT GREEN (4037 637);
DISPLAY INVISIBLE (4037 637);
FORCEPROP 2 LAST CDS_XR_PAGE_TITLE CR-98 : @BASEBOARD_FAB2_LIB.BASEBOARD_FAB2(SCH_1):PAGE98
J 0
(-3865 5875);
DISPLAY 0.638298 (-3865 5875);
PAINT PINK (-3865 5875);
DISPLAY INVISIBLE (-3865 5875);
WIRE 16 -1 (-1800 4550)(-1800 4450);
WIRE 16 -1 (-1800 2875)(-1800 2775);
WIRE 16 -1 (-1725 1825)(-1725 1925);
WIRE 16 -1 (-2025 1825)(-1725 1825);
WIRE 16 -1 (-2250 1825)(-2025 1825);
WIRE 16 -1 (-2025 1825)(-2025 1750);
WIRE 16 -1 (-2250 1950)(-2250 1825);
WIRE 16 -1 (250 4550)(250 4450);
WIRE 16 -1 (325 3500)(325 3600);
WIRE 16 -1 (25 3500)(325 3500);
WIRE 16 -1 (-200 3500)(25 3500);
WIRE 16 -1 (25 3500)(25 3425);
WIRE 16 -1 (-200 3625)(-200 3500);
WIRE 16 -1 (2400 4550)(2400 4450);
WIRE 16 -1 (2475 3500)(2475 3600);
WIRE 16 -1 (2175 3500)(2475 3500);
WIRE 16 -1 (1950 3500)(2175 3500);
WIRE 16 -1 (2175 3500)(2175 3425);
WIRE 16 -1 (1950 3625)(1950 3500);
WIRE 16 -1 (300 1825)(300 1925);
WIRE 16 -1 (0 1825)(300 1825);
WIRE 16 -1 (-225 1825)(0 1825);
WIRE 16 -1 (0 1825)(0 1750);
WIRE 16 -1 (-225 1950)(-225 1825);
WIRE 16 -1 (-1725 3500)(-1725 3600);
WIRE 16 -1 (-2025 3500)(-1725 3500);
WIRE 16 -1 (-2250 3500)(-2025 3500);
WIRE 16 -1 (-2025 3500)(-2025 3425);
WIRE 16 -1 (-2250 3625)(-2250 3500);
WIRE 16 -1 (2475 1800)(2475 1900);
WIRE 16 -1 (2175 1800)(2475 1800);
WIRE 16 -1 (1950 1800)(2175 1800);
WIRE 16 -1 (2175 1800)(2175 1725);
WIRE 16 -1 (1950 1925)(1950 1800);
WIRE 16 -1 (225 2875)(225 2775);
WIRE 16 -1 (2400 2850)(2400 2750);
WIRE 16 -1 (-2250 2350)(-2125 2350);
WIRE 16 -1 (-2250 2150)(-2250 2350);
WIRE 16 -1 (-2250 2350)(-2700 2350);
FORCEPROP 2 LAST SIG_NAME M_D_CPU_VREF
J 0
(-2625 2360);
DISPLAY 0.617021 (-2625 2360);
PAINT ORANGE (-2625 2360);
WIRE 16 -1 (-2250 4025)(-2125 4025);
WIRE 16 -1 (-2250 3825)(-2250 4025);
WIRE 16 -1 (-2250 4025)(-2700 4025);
FORCEPROP 2 LAST SIG_NAME M_A_CPU_VREF
J 0
(-2625 4035);
DISPLAY 0.617021 (-2625 4035);
PAINT ORANGE (-2625 4035);
WIRE 16 -1 (-1725 2125)(-1725 2350);
WIRE 16 -1 (-1425 2350)(-1725 2350);
WIRE 16 -1 (-1725 2350)(-1800 2350);
FORCEPROP 2 LAST SIG_NAME M_D_VREF
J 0
(-1750 2360);
DISPLAY 0.617021 (-1750 2360);
PAINT ORANGE (-1750 2360);
WIRE 16 -1 (-1800 2350)(-1800 2575);
WIRE 16 -1 (-1925 2350)(-1800 2350);
WIRE 16 -1 (-1925 4025)(-1800 4025);
WIRE 16 -1 (-1800 4025)(-1800 4250);
WIRE 16 -1 (-1725 4025)(-1800 4025);
FORCEPROP 2 LAST SIG_NAME M_A_VREF
J 0
(-1750 4035);
DISPLAY 0.617021 (-1750 4035);
PAINT ORANGE (-1750 4035);
WIRE 16 -1 (-1425 4025)(-1725 4025);
WIRE 16 -1 (-1725 3800)(-1725 4025);
WIRE 16 -1 (-225 2350)(-100 2350);
WIRE 16 -1 (-225 2150)(-225 2350);
WIRE 16 -1 (-225 2350)(-675 2350);
FORCEPROP 2 LAST SIG_NAME M_E_CPU_VREF
J 0
(-600 2360);
DISPLAY 0.617021 (-600 2360);
PAINT ORANGE (-600 2360);
WIRE 16 -1 (-200 4025)(-75 4025);
WIRE 16 -1 (-200 3825)(-200 4025);
WIRE 16 -1 (-200 4025)(-650 4025);
FORCEPROP 2 LAST SIG_NAME M_B_CPU_VREF
J 0
(-575 4035);
DISPLAY 0.617021 (-575 4035);
PAINT ORANGE (-575 4035);
WIRE 16 -1 (300 2125)(300 2350);
WIRE 16 -1 (600 2350)(300 2350);
WIRE 16 -1 (300 2350)(225 2350);
FORCEPROP 2 LAST SIG_NAME M_E_VREF
J 0
(275 2360);
DISPLAY 0.617021 (275 2360);
PAINT ORANGE (275 2360);
WIRE 16 -1 (225 2350)(225 2575);
WIRE 16 -1 (100 2350)(225 2350);
WIRE 16 -1 (125 4025)(250 4025);
WIRE 16 -1 (250 4025)(250 4250);
WIRE 16 -1 (325 4025)(250 4025);
FORCEPROP 2 LAST SIG_NAME M_B_VREF
J 0
(300 4035);
DISPLAY 0.617021 (300 4035);
PAINT ORANGE (300 4035);
WIRE 16 -1 (625 4025)(325 4025);
WIRE 16 -1 (325 3800)(325 4025);
WIRE 16 -1 (1950 2325)(2075 2325);
WIRE 16 -1 (1950 2125)(1950 2325);
WIRE 16 -1 (1950 2325)(1500 2325);
FORCEPROP 2 LAST SIG_NAME M_F_CPU_VREF
J 0
(1575 2335);
DISPLAY 0.617021 (1575 2335);
PAINT ORANGE (1575 2335);
WIRE 16 -1 (1950 4025)(2075 4025);
WIRE 16 -1 (1950 3825)(1950 4025);
WIRE 16 -1 (1950 4025)(1500 4025);
FORCEPROP 2 LAST SIG_NAME M_C_CPU_VREF
J 0
(1575 4035);
DISPLAY 0.617021 (1575 4035);
PAINT ORANGE (1575 4035);
WIRE 16 -1 (2475 2100)(2475 2325);
WIRE 16 -1 (2775 2325)(2475 2325);
WIRE 16 -1 (2475 2325)(2400 2325);
FORCEPROP 2 LAST SIG_NAME M_F_VREF
J 0
(2450 2335);
DISPLAY 0.617021 (2450 2335);
PAINT ORANGE (2450 2335);
WIRE 16 -1 (2400 2325)(2400 2550);
WIRE 16 -1 (2275 2325)(2400 2325);
WIRE 16 -1 (2275 4025)(2400 4025);
WIRE 16 -1 (2400 4025)(2400 4250);
WIRE 16 -1 (2475 4025)(2400 4025);
FORCEPROP 2 LAST SIG_NAME M_C_VREF
J 0
(2450 4035);
DISPLAY 0.617021 (2450 4035);
PAINT ORANGE (2450 4035);
WIRE 16 -1 (2775 4025)(2475 4025);
WIRE 16 -1 (2475 3800)(2475 4025);
DOT 1 (1950 2325);
DOT 1 (2175 1800);
DOT 1 (2400 2325);
DOT 1 (2475 2325);
DOT 1 (-225 2350);
DOT 1 (0 1825);
DOT 1 (225 2350);
DOT 1 (300 2350);
DOT 1 (1950 4025);
DOT 1 (2175 3500);
DOT 1 (2400 4025);
DOT 1 (2475 4025);
DOT 1 (-200 4025);
DOT 1 (25 3500);
DOT 1 (250 4025);
DOT 1 (325 4025);
DOT 1 (-1725 4025);
DOT 1 (-1800 4025);
DOT 1 (-2025 3500);
DOT 1 (-2250 4025);
DOT 1 (-2250 2350);
DOT 1 (-2025 1825);
DOT 1 (-1800 2350);
DOT 1 (-1725 2350);
QUIT
